(kicad_sch (version 20230121) (generator eeschema)

  (paper "A3")

  (title_block
    (title "Kria K26 Devboard")
    (date "2024-03-26")
    (rev "1.2.5")
    (comment 1 "www.antmicro.com")
    (comment 2 "Antmicro Ltd.")
  )

  (junction (at 358.14 93.98) (diameter 0) (color 0 0 0 0)
  )
  (junction (at 60.96 78.74) (diameter 0) (color 0 0 0 0)
  )
  (junction (at 48.26 78.74) (diameter 0) (color 0 0 0 0)
  )
  (junction (at 122.555 130.81) (diameter 0) (color 0 0 0 0)
  )
  (junction (at 122.555 128.27) (diameter 0) (color 0 0 0 0)
  )
  (junction (at 367.665 93.98) (diameter 0) (color 0 0 0 0)
  )
  (junction (at 351.536 69.85) (diameter 0) (color 0 0 0 0)
  )
  (junction (at 49.53 119.38) (diameter 0) (color 0 0 0 0)
  )
  (junction (at 358.14 101.6) (diameter 0) (color 0 0 0 0)
  )
  (junction (at 60.96 97.79) (diameter 0) (color 0 0 0 0)
  )
  (junction (at 44.45 220.98) (diameter 0) (color 0 0 0 0)
  )
  (junction (at 184.785 140.97) (diameter 0) (color 0 0 0 0)
  )
  (junction (at 122.555 81.28) (diameter 0) (color 0 0 0 0)
  )
  (junction (at 351.79 101.6) (diameter 0) (color 0 0 0 0)
  )
  (junction (at 38.1 78.74) (diameter 0) (color 0 0 0 0)
  )
  (junction (at 122.555 123.19) (diameter 0) (color 0 0 0 0)
  )
  (junction (at 55.88 78.74) (diameter 0) (color 0 0 0 0)
  )
  (junction (at 351.79 116.205) (diameter 0) (color 0 0 0 0)
  )
  (junction (at 351.79 85.09) (diameter 0) (color 0 0 0 0)
  )
  (junction (at 44.45 209.55) (diameter 0) (color 0 0 0 0)
  )
  (junction (at 287.02 82.55) (diameter 0) (color 0 0 0 0)
  )
  (junction (at 57.785 119.38) (diameter 0) (color 0 0 0 0)
  )
  (junction (at 379.73 93.98) (diameter 0) (color 0 0 0 0)
  )
  (junction (at 62.23 138.43) (diameter 0) (color 0 0 0 0)
  )
  (junction (at 55.88 220.98) (diameter 0) (color 0 0 0 0)
  )
  (junction (at 62.23 119.38) (diameter 0) (color 0 0 0 0)
  )
  (junction (at 39.37 119.38) (diameter 0) (color 0 0 0 0)
  )
  (junction (at 60.96 60.96) (diameter 0) (color 0 0 0 0)
  )
  (junction (at 358.14 85.09) (diameter 0) (color 0 0 0 0)
  )

  (no_connect (at 113.03 222.885))
  (no_connect (at 182.88 73.66))
  (no_connect (at 138.43 140.97))
  (no_connect (at 138.43 119.38))
  (no_connect (at 182.88 71.12))
  (no_connect (at 138.43 125.73))
  (no_connect (at 182.88 123.19))
  (no_connect (at 182.88 120.65))
  (no_connect (at 182.88 113.03))

  (bus_entry (at 116.84 93.98) (size 2.54 2.54)
    (stroke (width 0) (type default))
  )
  (bus_entry (at 116.84 105.41) (size 2.54 2.54)
    (stroke (width 0) (type default))
  )
  (bus_entry (at 238.76 111.76) (size 2.54 -2.54)
    (stroke (width 0) (type default))
  )
  (bus_entry (at 119.38 78.74) (size -2.54 -2.54)
    (stroke (width 0) (type default))
  )
  (bus_entry (at 238.76 114.3) (size 2.54 -2.54)
    (stroke (width 0) (type default))
  )
  (bus_entry (at 116.84 83.82) (size 2.54 2.54)
    (stroke (width 0) (type default))
  )
  (bus_entry (at 238.76 109.22) (size 2.54 -2.54)
    (stroke (width 0) (type default))
  )
  (bus_entry (at 116.84 107.95) (size 2.54 2.54)
    (stroke (width 0) (type default))
  )
  (bus_entry (at 119.38 99.06) (size -2.54 -2.54)
    (stroke (width 0) (type default))
  )
  (bus_entry (at 116.84 110.49) (size 2.54 2.54)
    (stroke (width 0) (type default))
  )
  (bus_entry (at 116.84 78.74) (size 2.54 2.54)
    (stroke (width 0) (type default))
  )
  (bus_entry (at 116.84 91.44) (size 2.54 2.54)
    (stroke (width 0) (type default))
  )
  (bus_entry (at 238.76 116.84) (size 2.54 -2.54)
    (stroke (width 0) (type default))
  )
  (bus_entry (at 116.84 86.36) (size 2.54 2.54)
    (stroke (width 0) (type default))
  )
  (bus_entry (at 116.84 113.03) (size 2.54 2.54)
    (stroke (width 0) (type default))
  )
  (bus_entry (at 116.84 102.87) (size 2.54 2.54)
    (stroke (width 0) (type default))
  )
  (bus_entry (at 116.84 100.33) (size 2.54 2.54)
    (stroke (width 0) (type default))
  )
  (bus_entry (at 116.84 88.9) (size 2.54 2.54)
    (stroke (width 0) (type default))
  )

  (wire (pts (xy 60.96 78.74) (xy 60.96 80.01))
    (stroke (width 0) (type default))
  )
  (wire (pts (xy 53.086 220.98) (xy 44.45 220.98))
    (stroke (width 0) (type default))
  )
  (wire (pts (xy 351.79 101.6) (xy 358.14 101.6))
    (stroke (width 0) (type default))
  )
  (wire (pts (xy 138.43 128.27) (xy 133.35 128.27))
    (stroke (width 0) (type default))
  )
  (wire (pts (xy 138.43 96.52) (xy 119.38 96.52))
    (stroke (width 0) (type default))
  )
  (wire (pts (xy 185.42 83.82) (xy 250.19 83.82))
    (stroke (width 0) (type default))
  )
  (wire (pts (xy 182.88 110.49) (xy 190.5 110.49))
    (stroke (width 0) (type default))
  )
  (wire (pts (xy 39.37 119.38) (xy 39.37 120.65))
    (stroke (width 0) (type default))
  )
  (bus (pts (xy 238.76 109.22) (xy 238.76 111.76))
    (stroke (width 0) (type default))
  )

  (wire (pts (xy 187.325 86.36) (xy 250.19 86.36))
    (stroke (width 0) (type default))
  )
  (wire (pts (xy 119.38 110.49) (xy 138.43 110.49))
    (stroke (width 0) (type default))
  )
  (wire (pts (xy 184.785 137.16) (xy 184.785 140.97))
    (stroke (width 0) (type default))
  )
  (wire (pts (xy 351.79 116.205) (xy 358.14 116.205))
    (stroke (width 0) (type default))
  )
  (bus (pts (xy 116.84 110.49) (xy 116.84 113.03))
    (stroke (width 0) (type default))
  )

  (wire (pts (xy 193.04 93.98) (xy 250.19 93.98))
    (stroke (width 0) (type default))
  )
  (wire (pts (xy 133.35 134.62) (xy 138.43 134.62))
    (stroke (width 0) (type default))
  )
  (wire (pts (xy 367.665 95.25) (xy 367.665 93.98))
    (stroke (width 0) (type default))
  )
  (wire (pts (xy 182.88 68.58) (xy 187.96 68.58))
    (stroke (width 0) (type default))
  )
  (wire (pts (xy 55.88 78.74) (xy 55.88 97.79))
    (stroke (width 0) (type default))
  )
  (wire (pts (xy 122.555 121.92) (xy 122.555 123.19))
    (stroke (width 0) (type default))
  )
  (wire (pts (xy 49.53 119.38) (xy 57.785 119.38))
    (stroke (width 0) (type default))
  )
  (wire (pts (xy 271.78 106.68) (xy 287.02 106.68))
    (stroke (width 0) (type default))
  )
  (wire (pts (xy 71.12 80.01) (xy 71.12 78.74))
    (stroke (width 0) (type default))
  )
  (wire (pts (xy 138.43 113.03) (xy 119.38 113.03))
    (stroke (width 0) (type default))
  )
  (wire (pts (xy 44.45 220.98) (xy 44.45 217.805))
    (stroke (width 0) (type default))
  )
  (wire (pts (xy 55.88 97.79) (xy 60.96 97.79))
    (stroke (width 0) (type default))
  )
  (wire (pts (xy 122.555 134.62) (xy 128.27 134.62))
    (stroke (width 0) (type default))
  )
  (bus (pts (xy 238.76 111.76) (xy 238.76 114.3))
    (stroke (width 0) (type default))
  )

  (wire (pts (xy 55.88 232.41) (xy 55.88 227.965))
    (stroke (width 0) (type default))
  )
  (wire (pts (xy 182.88 78.74) (xy 250.19 78.74))
    (stroke (width 0) (type default))
  )
  (wire (pts (xy 311.785 121.92) (xy 294.64 121.92))
    (stroke (width 0) (type default))
  )
  (wire (pts (xy 55.88 212.725) (xy 55.88 209.55))
    (stroke (width 0) (type default))
  )
  (wire (pts (xy 119.38 105.41) (xy 138.43 105.41))
    (stroke (width 0) (type default))
  )
  (wire (pts (xy 128.27 128.27) (xy 122.555 128.27))
    (stroke (width 0) (type default))
  )
  (wire (pts (xy 358.14 93.98) (xy 367.665 93.98))
    (stroke (width 0) (type default))
  )
  (wire (pts (xy 351.536 69.85) (xy 351.536 71.12))
    (stroke (width 0) (type default))
  )
  (wire (pts (xy 189.23 93.98) (xy 182.88 93.98))
    (stroke (width 0) (type default))
  )
  (wire (pts (xy 138.43 93.98) (xy 119.38 93.98))
    (stroke (width 0) (type default))
  )
  (wire (pts (xy 71.12 60.96) (xy 60.96 60.96))
    (stroke (width 0) (type default))
  )
  (wire (pts (xy 271.78 101.6) (xy 296.545 101.6))
    (stroke (width 0) (type default))
  )
  (wire (pts (xy 184.785 128.27) (xy 184.785 132.08))
    (stroke (width 0) (type default))
  )
  (wire (pts (xy 122.555 123.19) (xy 113.665 123.19))
    (stroke (width 0) (type default))
  )
  (wire (pts (xy 55.88 220.98) (xy 55.88 217.805))
    (stroke (width 0) (type default))
  )
  (wire (pts (xy 122.555 130.81) (xy 122.555 134.62))
    (stroke (width 0) (type default))
  )
  (wire (pts (xy 71.12 62.23) (xy 71.12 60.96))
    (stroke (width 0) (type default))
  )
  (wire (pts (xy 38.1 119.38) (xy 39.37 119.38))
    (stroke (width 0) (type default))
  )
  (wire (pts (xy 38.1 78.74) (xy 38.1 80.645))
    (stroke (width 0) (type default))
  )
  (wire (pts (xy 84.455 220.345) (xy 86.995 220.345))
    (stroke (width 0) (type default))
  )
  (wire (pts (xy 128.27 123.19) (xy 122.555 123.19))
    (stroke (width 0) (type default))
  )
  (wire (pts (xy 62.23 119.38) (xy 72.39 119.38))
    (stroke (width 0) (type default))
  )
  (wire (pts (xy 39.37 209.55) (xy 44.45 209.55))
    (stroke (width 0) (type default))
  )
  (wire (pts (xy 351.536 69.85) (xy 358.14 69.85))
    (stroke (width 0) (type default))
  )
  (wire (pts (xy 182.88 115.57) (xy 190.5 115.57))
    (stroke (width 0) (type default))
  )
  (bus (pts (xy 238.76 114.3) (xy 238.76 116.84))
    (stroke (width 0) (type default))
  )

  (wire (pts (xy 184.785 140.97) (xy 182.88 140.97))
    (stroke (width 0) (type default))
  )
  (wire (pts (xy 44.45 232.41) (xy 44.45 227.965))
    (stroke (width 0) (type default))
  )
  (wire (pts (xy 55.88 60.96) (xy 55.88 78.74))
    (stroke (width 0) (type default))
  )
  (wire (pts (xy 241.3 114.3) (xy 250.19 114.3))
    (stroke (width 0) (type default))
  )
  (wire (pts (xy 49.53 120.65) (xy 49.53 119.38))
    (stroke (width 0) (type default))
  )
  (bus (pts (xy 116.84 107.95) (xy 116.84 110.49))
    (stroke (width 0) (type default))
  )

  (wire (pts (xy 296.545 82.55) (xy 296.545 87.63))
    (stroke (width 0) (type default))
  )
  (wire (pts (xy 44.45 212.725) (xy 44.45 209.55))
    (stroke (width 0) (type default))
  )
  (wire (pts (xy 44.45 222.885) (xy 44.45 220.98))
    (stroke (width 0) (type default))
  )
  (wire (pts (xy 36.576 78.74) (xy 38.1 78.74))
    (stroke (width 0) (type default))
  )
  (wire (pts (xy 222.885 101.6) (xy 250.19 101.6))
    (stroke (width 0) (type default))
  )
  (wire (pts (xy 351.79 85.09) (xy 351.79 86.36))
    (stroke (width 0) (type default))
  )
  (wire (pts (xy 64.008 220.98) (xy 55.88 220.98))
    (stroke (width 0) (type default))
  )
  (wire (pts (xy 71.12 97.79) (xy 60.96 97.79))
    (stroke (width 0) (type default))
  )
  (wire (pts (xy 187.325 88.9) (xy 187.325 86.36))
    (stroke (width 0) (type default))
  )
  (wire (pts (xy 296.545 104.14) (xy 296.545 105.41))
    (stroke (width 0) (type default))
  )
  (bus (pts (xy 237.49 119.38) (xy 238.76 119.38))
    (stroke (width 0) (type default))
  )
  (bus (pts (xy 116.84 93.98) (xy 116.84 96.52))
    (stroke (width 0) (type default))
  )

  (wire (pts (xy 113.03 220.345) (xy 110.49 220.345))
    (stroke (width 0) (type default))
  )
  (wire (pts (xy 48.26 78.74) (xy 48.26 80.645))
    (stroke (width 0) (type default))
  )
  (wire (pts (xy 287.02 106.68) (xy 287.02 92.71))
    (stroke (width 0) (type default))
  )
  (wire (pts (xy 351.79 116.205) (xy 351.79 117.475))
    (stroke (width 0) (type default))
  )
  (wire (pts (xy 340.106 69.85) (xy 351.536 69.85))
    (stroke (width 0) (type default))
  )
  (wire (pts (xy 48.26 78.74) (xy 55.88 78.74))
    (stroke (width 0) (type default))
  )
  (bus (pts (xy 116.84 88.9) (xy 116.84 91.44))
    (stroke (width 0) (type default))
  )

  (wire (pts (xy 119.38 99.06) (xy 138.43 99.06))
    (stroke (width 0) (type default))
  )
  (wire (pts (xy 340.36 86.36) (xy 340.36 85.09))
    (stroke (width 0) (type default))
  )
  (wire (pts (xy 271.78 109.22) (xy 287.02 109.22))
    (stroke (width 0) (type default))
  )
  (bus (pts (xy 116.84 76.2) (xy 116.84 78.74))
    (stroke (width 0) (type default))
  )

  (wire (pts (xy 138.43 88.9) (xy 119.38 88.9))
    (stroke (width 0) (type default))
  )
  (wire (pts (xy 340.36 101.6) (xy 351.79 101.6))
    (stroke (width 0) (type default))
  )
  (wire (pts (xy 62.23 138.43) (xy 62.23 139.7))
    (stroke (width 0) (type default))
  )
  (bus (pts (xy 116.84 78.74) (xy 116.84 83.82))
    (stroke (width 0) (type default))
  )

  (wire (pts (xy 138.43 86.36) (xy 119.38 86.36))
    (stroke (width 0) (type default))
  )
  (wire (pts (xy 137.414 220.345) (xy 132.08 220.345))
    (stroke (width 0) (type default))
  )
  (wire (pts (xy 57.785 119.38) (xy 57.785 138.43))
    (stroke (width 0) (type default))
  )
  (wire (pts (xy 379.73 93.98) (xy 382.905 93.98))
    (stroke (width 0) (type default))
  )
  (wire (pts (xy 194.945 104.14) (xy 194.945 96.52))
    (stroke (width 0) (type default))
  )
  (wire (pts (xy 55.88 78.74) (xy 60.96 78.74))
    (stroke (width 0) (type default))
  )
  (bus (pts (xy 116.84 96.52) (xy 116.84 100.33))
    (stroke (width 0) (type default))
  )

  (wire (pts (xy 133.35 74.93) (xy 138.43 74.93))
    (stroke (width 0) (type default))
  )
  (wire (pts (xy 62.23 119.38) (xy 62.23 120.65))
    (stroke (width 0) (type default))
  )
  (wire (pts (xy 60.96 97.79) (xy 60.96 99.06))
    (stroke (width 0) (type default))
  )
  (wire (pts (xy 138.43 115.57) (xy 119.38 115.57))
    (stroke (width 0) (type default))
  )
  (wire (pts (xy 185.42 86.36) (xy 185.42 83.82))
    (stroke (width 0) (type default))
  )
  (wire (pts (xy 72.39 138.43) (xy 62.23 138.43))
    (stroke (width 0) (type default))
  )
  (wire (pts (xy 358.14 85.09) (xy 358.14 93.98))
    (stroke (width 0) (type default))
  )
  (wire (pts (xy 60.96 78.74) (xy 71.12 78.74))
    (stroke (width 0) (type default))
  )
  (wire (pts (xy 351.79 85.09) (xy 340.36 85.09))
    (stroke (width 0) (type default))
  )
  (wire (pts (xy 119.38 107.95) (xy 138.43 107.95))
    (stroke (width 0) (type default))
  )
  (wire (pts (xy 184.785 140.97) (xy 184.785 142.875))
    (stroke (width 0) (type default))
  )
  (bus (pts (xy 114.935 76.2) (xy 116.84 76.2))
    (stroke (width 0) (type default))
  )

  (wire (pts (xy 358.14 101.6) (xy 358.14 116.205))
    (stroke (width 0) (type default))
  )
  (wire (pts (xy 182.88 81.28) (xy 250.19 81.28))
    (stroke (width 0) (type default))
  )
  (wire (pts (xy 55.88 222.885) (xy 55.88 220.98))
    (stroke (width 0) (type default))
  )
  (bus (pts (xy 116.84 100.33) (xy 116.84 102.87))
    (stroke (width 0) (type default))
  )

  (wire (pts (xy 138.43 91.44) (xy 119.38 91.44))
    (stroke (width 0) (type default))
  )
  (wire (pts (xy 271.78 104.14) (xy 296.545 104.14))
    (stroke (width 0) (type default))
  )
  (wire (pts (xy 60.96 60.96) (xy 60.96 62.23))
    (stroke (width 0) (type default))
  )
  (wire (pts (xy 122.555 116.84) (xy 122.555 81.28))
    (stroke (width 0) (type default))
  )
  (bus (pts (xy 116.84 102.87) (xy 116.84 105.41))
    (stroke (width 0) (type default))
  )

  (wire (pts (xy 191.135 96.52) (xy 182.88 96.52))
    (stroke (width 0) (type default))
  )
  (wire (pts (xy 241.3 111.76) (xy 250.19 111.76))
    (stroke (width 0) (type default))
  )
  (wire (pts (xy 122.555 81.28) (xy 138.43 81.28))
    (stroke (width 0) (type default))
  )
  (wire (pts (xy 182.88 101.6) (xy 193.04 101.6))
    (stroke (width 0) (type default))
  )
  (bus (pts (xy 116.84 83.82) (xy 116.84 86.36))
    (stroke (width 0) (type default))
  )

  (wire (pts (xy 133.35 71.12) (xy 138.43 71.12))
    (stroke (width 0) (type default))
  )
  (wire (pts (xy 119.38 81.28) (xy 122.555 81.28))
    (stroke (width 0) (type default))
  )
  (wire (pts (xy 111.125 226.695) (xy 111.125 225.425))
    (stroke (width 0) (type default))
  )
  (wire (pts (xy 72.39 120.65) (xy 72.39 119.38))
    (stroke (width 0) (type default))
  )
  (wire (pts (xy 287.02 82.55) (xy 282.575 82.55))
    (stroke (width 0) (type default))
  )
  (wire (pts (xy 57.785 138.43) (xy 62.23 138.43))
    (stroke (width 0) (type default))
  )
  (wire (pts (xy 138.43 123.19) (xy 133.35 123.19))
    (stroke (width 0) (type default))
  )
  (wire (pts (xy 296.545 101.6) (xy 296.545 92.71))
    (stroke (width 0) (type default))
  )
  (wire (pts (xy 39.37 119.38) (xy 49.53 119.38))
    (stroke (width 0) (type default))
  )
  (bus (pts (xy 116.84 86.36) (xy 116.84 88.9))
    (stroke (width 0) (type default))
  )
  (bus (pts (xy 116.84 105.41) (xy 116.84 107.95))
    (stroke (width 0) (type default))
  )

  (wire (pts (xy 138.43 78.74) (xy 119.38 78.74))
    (stroke (width 0) (type default))
  )
  (wire (pts (xy 241.3 106.68) (xy 250.19 106.68))
    (stroke (width 0) (type default))
  )
  (wire (pts (xy 367.665 93.98) (xy 379.73 93.98))
    (stroke (width 0) (type default))
  )
  (wire (pts (xy 138.43 130.81) (xy 133.35 130.81))
    (stroke (width 0) (type default))
  )
  (wire (pts (xy 287.02 116.84) (xy 287.02 109.22))
    (stroke (width 0) (type default))
  )
  (wire (pts (xy 57.785 119.38) (xy 62.23 119.38))
    (stroke (width 0) (type default))
  )
  (wire (pts (xy 191.135 91.44) (xy 191.135 96.52))
    (stroke (width 0) (type default))
  )
  (wire (pts (xy 287.02 82.55) (xy 296.545 82.55))
    (stroke (width 0) (type default))
  )
  (wire (pts (xy 71.12 99.06) (xy 71.12 97.79))
    (stroke (width 0) (type default))
  )
  (wire (pts (xy 86.995 222.885) (xy 86.995 220.345))
    (stroke (width 0) (type default))
  )
  (wire (pts (xy 340.36 117.475) (xy 340.36 116.205))
    (stroke (width 0) (type default))
  )
  (wire (pts (xy 44.45 209.55) (xy 55.88 209.55))
    (stroke (width 0) (type default))
  )
  (wire (pts (xy 340.106 71.12) (xy 340.106 69.85))
    (stroke (width 0) (type default))
  )
  (wire (pts (xy 379.73 93.98) (xy 379.73 95.25))
    (stroke (width 0) (type default))
  )
  (wire (pts (xy 138.43 102.87) (xy 119.38 102.87))
    (stroke (width 0) (type default))
  )
  (bus (pts (xy 116.84 91.44) (xy 116.84 93.98))
    (stroke (width 0) (type default))
  )

  (wire (pts (xy 122.555 128.27) (xy 122.555 130.81))
    (stroke (width 0) (type default))
  )
  (wire (pts (xy 182.88 86.36) (xy 185.42 86.36))
    (stroke (width 0) (type default))
  )
  (wire (pts (xy 182.88 88.9) (xy 187.325 88.9))
    (stroke (width 0) (type default))
  )
  (wire (pts (xy 133.35 68.58) (xy 138.43 68.58))
    (stroke (width 0) (type default))
  )
  (wire (pts (xy 60.96 60.96) (xy 55.88 60.96))
    (stroke (width 0) (type default))
  )
  (wire (pts (xy 304.165 110.49) (xy 311.785 110.49))
    (stroke (width 0) (type default))
  )
  (wire (pts (xy 48.26 78.74) (xy 38.1 78.74))
    (stroke (width 0) (type default))
  )
  (wire (pts (xy 227.33 104.14) (xy 227.33 106.68))
    (stroke (width 0) (type default))
  )
  (wire (pts (xy 111.125 225.425) (xy 113.03 225.425))
    (stroke (width 0) (type default))
  )
  (wire (pts (xy 340.36 116.205) (xy 351.79 116.205))
    (stroke (width 0) (type default))
  )
  (wire (pts (xy 189.23 88.9) (xy 189.23 93.98))
    (stroke (width 0) (type default))
  )
  (wire (pts (xy 194.945 96.52) (xy 250.19 96.52))
    (stroke (width 0) (type default))
  )
  (wire (pts (xy 182.88 104.14) (xy 194.945 104.14))
    (stroke (width 0) (type default))
  )
  (wire (pts (xy 287.02 87.63) (xy 287.02 82.55))
    (stroke (width 0) (type default))
  )
  (wire (pts (xy 193.04 101.6) (xy 193.04 93.98))
    (stroke (width 0) (type default))
  )
  (wire (pts (xy 358.14 93.98) (xy 358.14 101.6))
    (stroke (width 0) (type default))
  )
  (wire (pts (xy 227.33 104.14) (xy 250.19 104.14))
    (stroke (width 0) (type default))
  )
  (wire (pts (xy 222.885 106.68) (xy 222.885 101.6))
    (stroke (width 0) (type default))
  )
  (wire (pts (xy 182.88 128.27) (xy 184.785 128.27))
    (stroke (width 0) (type default))
  )
  (wire (pts (xy 351.79 101.6) (xy 351.79 102.87))
    (stroke (width 0) (type default))
  )
  (wire (pts (xy 351.79 85.09) (xy 358.14 85.09))
    (stroke (width 0) (type default))
  )
  (wire (pts (xy 241.3 109.22) (xy 250.19 109.22))
    (stroke (width 0) (type default))
  )
  (wire (pts (xy 131.445 138.43) (xy 138.43 138.43))
    (stroke (width 0) (type default))
  )
  (wire (pts (xy 358.14 69.85) (xy 358.14 85.09))
    (stroke (width 0) (type default))
  )
  (bus (pts (xy 238.76 116.84) (xy 238.76 119.38))
    (stroke (width 0) (type default))
  )

  (wire (pts (xy 271.78 114.3) (xy 275.59 114.3))
    (stroke (width 0) (type default))
  )
  (wire (pts (xy 122.555 130.81) (xy 128.27 130.81))
    (stroke (width 0) (type default))
  )
  (wire (pts (xy 72.39 139.7) (xy 72.39 138.43))
    (stroke (width 0) (type default))
  )
  (wire (pts (xy 189.23 88.9) (xy 250.19 88.9))
    (stroke (width 0) (type default))
  )
  (wire (pts (xy 340.36 102.87) (xy 340.36 101.6))
    (stroke (width 0) (type default))
  )
  (wire (pts (xy 122.555 123.19) (xy 122.555 128.27))
    (stroke (width 0) (type default))
  )
  (wire (pts (xy 191.135 91.44) (xy 250.19 91.44))
    (stroke (width 0) (type default))
  )

  (text "CLK is matched to data lanes, the device tree should use \"rgmii-id\""
    (at 229.87 281.94 0)
    (effects (font (size 1.27 1.27)) (justify left bottom))
  )
  (text "Address = 0x01" (at 45.72 256.54 90)
    (effects (font (size 1.27 1.27)) (justify left bottom))
  )
  (text "ETH0 - PD PoE" (at 12.7 17.78 0)
    (effects (font (size 2.54 2.54) (thickness 0.508) bold) (justify left bottom))
  )
  (text "Autoneg disable =  false" (at 57.15 264.16 90)
    (effects (font (size 1.27 1.27)) (justify left bottom))
  )
  (text "NOTE:" (at 234.95 278.13 0)
    (effects (font (size 1.27 1.27) (thickness 0.254) bold) (justify right bottom))
  )
  (text "Strap Configuration" (at 59.69 198.12 0)
    (effects (font (size 1.27 1.27) (thickness 0.254) bold) (justify right bottom))
  )

  (label "MIO73" (at 129.54 110.49 0) (fields_autoplaced)
    (effects (font (size 1.27 1.27)) (justify left bottom))
  )
  (label "TD_D_N" (at 241.3 96.52 0) (fields_autoplaced)
    (effects (font (size 1.27 1.27)) (justify left bottom))
  )
  (label "MIO69" (at 129.54 86.36 0) (fields_autoplaced)
    (effects (font (size 1.27 1.27)) (justify left bottom))
  )
  (label "TD_A_N" (at 241.3 81.28 0) (fields_autoplaced)
    (effects (font (size 1.27 1.27)) (justify left bottom))
  )
  (label "MIO71" (at 53.086 220.98 180) (fields_autoplaced)
    (effects (font (size 1.27 1.27)) (justify right bottom))
  )
  (label "MIO72" (at 129.54 107.95 0) (fields_autoplaced)
    (effects (font (size 1.27 1.27)) (justify left bottom))
  )
  (label "MIO67" (at 129.54 93.98 0) (fields_autoplaced)
    (effects (font (size 1.27 1.27)) (justify left bottom))
  )
  (label "TD_B_N" (at 241.3 86.36 0) (fields_autoplaced)
    (effects (font (size 1.27 1.27)) (justify left bottom))
  )
  (label "MIO71" (at 129.54 105.41 0) (fields_autoplaced)
    (effects (font (size 1.27 1.27)) (justify left bottom))
  )
  (label "MIO66" (at 129.54 91.44 0) (fields_autoplaced)
    (effects (font (size 1.27 1.27)) (justify left bottom))
  )
  (label "MIO64" (at 129.54 99.06 0) (fields_autoplaced)
    (effects (font (size 1.27 1.27)) (justify left bottom))
  )
  (label "MIO76" (at 129.54 78.74 0) (fields_autoplaced)
    (effects (font (size 1.27 1.27)) (justify left bottom))
  )
  (label "MIO74" (at 129.54 113.03 0) (fields_autoplaced)
    (effects (font (size 1.27 1.27)) (justify left bottom))
  )
  (label "POE_VC4" (at 241.3 114.3 0) (fields_autoplaced)
    (effects (font (size 1.27 1.27)) (justify left bottom))
  )
  (label "TD_A_P" (at 241.3 78.74 0) (fields_autoplaced)
    (effects (font (size 1.27 1.27)) (justify left bottom))
  )
  (label "TD_C_P" (at 241.3 88.9 0) (fields_autoplaced)
    (effects (font (size 1.27 1.27)) (justify left bottom))
  )
  (label "MIO65" (at 129.54 88.9 0) (fields_autoplaced)
    (effects (font (size 1.27 1.27)) (justify left bottom))
  )
  (label "MIO75" (at 129.54 102.87 0) (fields_autoplaced)
    (effects (font (size 1.27 1.27)) (justify left bottom))
  )
  (label "X_I" (at 137.414 220.345 180) (fields_autoplaced)
    (effects (font (size 1.27 1.27)) (justify right bottom))
  )
  (label "TD_B_P" (at 241.3 83.82 0) (fields_autoplaced)
    (effects (font (size 1.27 1.27)) (justify left bottom))
  )
  (label "LED2" (at 311.785 110.49 180) (fields_autoplaced)
    (effects (font (size 1.27 1.27)) (justify right bottom))
  )
  (label "TD_D_P" (at 241.3 93.98 0) (fields_autoplaced)
    (effects (font (size 1.27 1.27)) (justify left bottom))
  )
  (label "POE_VC1" (at 241.3 106.68 0) (fields_autoplaced)
    (effects (font (size 1.27 1.27)) (justify left bottom))
  )
  (label "X_I" (at 131.445 138.43 0) (fields_autoplaced)
    (effects (font (size 1.27 1.27)) (justify left bottom))
  )
  (label "MIO68" (at 129.54 96.52 0) (fields_autoplaced)
    (effects (font (size 1.27 1.27)) (justify left bottom))
  )
  (label "LED0" (at 190.5 110.49 180) (fields_autoplaced)
    (effects (font (size 1.27 1.27)) (justify right bottom))
  )
  (label "POE_VC3" (at 241.3 111.76 0) (fields_autoplaced)
    (effects (font (size 1.27 1.27)) (justify left bottom))
  )
  (label "POE_VC2" (at 241.3 109.22 0) (fields_autoplaced)
    (effects (font (size 1.27 1.27)) (justify left bottom))
  )
  (label "LED0" (at 311.785 121.92 180) (fields_autoplaced)
    (effects (font (size 1.27 1.27)) (justify right bottom))
  )
  (label "MIO77" (at 129.54 81.28 0) (fields_autoplaced)
    (effects (font (size 1.27 1.27)) (justify left bottom))
  )
  (label "LED2" (at 190.5 115.57 180) (fields_autoplaced)
    (effects (font (size 1.27 1.27)) (justify right bottom))
  )
  (label "MIO75" (at 64.008 220.98 180) (fields_autoplaced)
    (effects (font (size 1.27 1.27)) (justify right bottom))
  )
  (label "TD_C_N" (at 241.3 91.44 0) (fields_autoplaced)
    (effects (font (size 1.27 1.27)) (justify left bottom))
  )
  (label "MIO70" (at 129.54 115.57 0) (fields_autoplaced)
    (effects (font (size 1.27 1.27)) (justify left bottom))
  )

  (global_label "PS_1V0" (shape input) (at 382.905 93.98 0) (fields_autoplaced)
    (effects (font (size 1.27 1.27)) (justify left))
    (property "Intersheetrefs" "${INTERSHEET_REFS}" (at -5.715 5.08 0)
      (effects (font (size 1.27 1.27)) hide)
    )
  )
  (global_label "PS_1V8" (shape input) (at 84.455 220.345 180) (fields_autoplaced)
    (effects (font (size 1.27 1.27)) (justify right))
    (property "Intersheetrefs" "${INTERSHEET_REFS}" (at -131.445 301.625 0)
      (effects (font (size 1.27 1.27)) hide)
    )
  )
  (global_label "PS_1V0" (shape input) (at 187.96 68.58 0) (fields_autoplaced)
    (effects (font (size 1.27 1.27)) (justify left))
    (property "Intersheetrefs" "${INTERSHEET_REFS}" (at -8.89 0 0)
      (effects (font (size 1.27 1.27)) hide)
    )
  )
  (global_label "PS_2V5" (shape input) (at 38.1 119.38 180) (fields_autoplaced)
    (effects (font (size 1.27 1.27)) (justify right))
    (property "Intersheetrefs" "${INTERSHEET_REFS}" (at 0 0 0)
      (effects (font (size 1.27 1.27)) hide)
    )
  )
  (global_label "PS_1V8" (shape input) (at 133.35 68.58 180) (fields_autoplaced)
    (effects (font (size 1.27 1.27)) (justify right))
    (property "Intersheetrefs" "${INTERSHEET_REFS}" (at 7.62 0 0)
      (effects (font (size 1.27 1.27)) hide)
    )
  )
  (global_label "PS_1V8" (shape input) (at 36.576 78.74 180) (fields_autoplaced)
    (effects (font (size 1.27 1.27)) (justify right))
    (property "Intersheetrefs" "${INTERSHEET_REFS}" (at -1.524 0 0)
      (effects (font (size 1.27 1.27)) hide)
    )
  )
  (global_label "PS_2V5" (shape input) (at 133.35 71.12 180) (fields_autoplaced)
    (effects (font (size 1.27 1.27)) (justify right))
    (property "Intersheetrefs" "${INTERSHEET_REFS}" (at 7.62 -7.62 0)
      (effects (font (size 1.27 1.27)) hide)
    )
  )
  (global_label "PS_1V8" (shape input) (at 110.49 220.345 180) (fields_autoplaced)
    (effects (font (size 1.27 1.27)) (justify right))
    (property "Intersheetrefs" "${INTERSHEET_REFS}" (at -100.33 323.215 0)
      (effects (font (size 1.27 1.27)) hide)
    )
  )
  (global_label "PS_1V8" (shape input) (at 39.37 209.55 180) (fields_autoplaced)
    (effects (font (size 1.27 1.27)) (justify right))
    (property "Intersheetrefs" "${INTERSHEET_REFS}" (at -170.18 254 0)
      (effects (font (size 1.27 1.27)) hide)
    )
  )
  (global_label "PS_2V5" (shape input) (at 282.575 82.55 180) (fields_autoplaced)
    (effects (font (size 1.27 1.27)) (justify right))
    (property "Intersheetrefs" "${INTERSHEET_REFS}" (at 201.295 393.7 0)
      (effects (font (size 1.27 1.27)) hide)
    )
  )
  (global_label "SH_UP" (shape input) (at 275.59 114.3 0) (fields_autoplaced)
    (effects (font (size 1.27 1.27)) (justify left))
    (property "Intersheetrefs" "${INTERSHEET_REFS}" (at 138.43 372.11 0)
      (effects (font (size 1.27 1.27)) hide)
    )
  )
  (global_label "PS_1V8" (shape input) (at 113.665 123.19 180) (fields_autoplaced)
    (effects (font (size 1.27 1.27)) (justify right))
    (property "Intersheetrefs" "${INTERSHEET_REFS}" (at -13.335 232.41 0)
      (effects (font (size 1.27 1.27)) hide)
    )
  )
  (global_label "PS_1V8" (shape input) (at 133.35 68.58 180) (fields_autoplaced)
    (effects (font (size 1.27 1.27)) (justify right))
    (property "Intersheetrefs" "${INTERSHEET_REFS}" (at 7.62 0 0)
      (effects (font (size 1.27 1.27)) hide)
    )
  )

  (hierarchical_label "MIO[64..77]" (shape input) (at 114.935 76.2 180) (fields_autoplaced)
    (effects (font (size 1.27 1.27)) (justify right))
  )
  (hierarchical_label "POE_VC[1..4]" (shape input) (at 237.49 119.38 180) (fields_autoplaced)
    (effects (font (size 1.27 1.27)) (justify right))
  )
  (hierarchical_label "~{ETH_RESET}" (shape input) (at 133.35 74.93 180) (fields_autoplaced)
    (effects (font (size 1.27 1.27)) (justify right))
  )

  (symbol (lib_id "kria-k26-devboard:GND") (at 184.785 142.875 0) (unit 1)
    (in_bom yes) (on_board yes) (dnp no) (fields_autoplaced)
    (property "Reference" "#PWR0116" (at 184.785 149.225 0)
      (effects (font (size 1.27 1.27)) hide)
    )
    (property "Value" "GND" (at 184.785 147.955 0)
      (effects (font (size 1.27 1.27)))
    )
    (property "Footprint" "" (at 193.675 150.495 0)
      (effects (font (size 1.27 1.27) (thickness 0.15)) (justify left bottom) hide)
    )
    (property "Datasheet" "" (at 193.675 155.575 0)
      (effects (font (size 1.27 1.27) (thickness 0.15)) (justify left bottom) hide)
    )
    (property "Author" "Antmicro" (at 193.675 150.495 0)
      (effects (font (size 1.27 1.27) (thickness 0.15)) (justify left bottom) hide)
    )
    (property "License" "Apache-2.0" (at 193.675 153.035 0)
      (effects (font (size 1.27 1.27) (thickness 0.15)) (justify left bottom) hide)
    )
    (pin "1")
    (instances
      (project "kria-k26-devboard"
        (path ""
          (reference "#PWR0116") (unit 1)
        )
      )
    )
  )

  (symbol (lib_id "kria-k26-devboard:GND") (at 287.02 127 0) (mirror y) (unit 1)
    (in_bom yes) (on_board yes) (dnp no)
    (property "Reference" "#PWR0118" (at 287.02 133.35 0)
      (effects (font (size 1.27 1.27)) hide)
    )
    (property "Value" "GND" (at 287.02 130.81 0)
      (effects (font (size 1.27 1.27)))
    )
    (property "Footprint" "" (at 278.13 134.62 0)
      (effects (font (size 1.27 1.27) (thickness 0.15)) (justify left bottom) hide)
    )
    (property "Datasheet" "" (at 278.13 139.7 0)
      (effects (font (size 1.27 1.27) (thickness 0.15)) (justify left bottom) hide)
    )
    (property "Author" "Antmicro" (at 278.13 134.62 0)
      (effects (font (size 1.27 1.27) (thickness 0.15)) (justify left bottom) hide)
    )
    (property "License" "Apache-2.0" (at 278.13 137.16 0)
      (effects (font (size 1.27 1.27) (thickness 0.15)) (justify left bottom) hide)
    )
    (pin "1")
    (instances
      (project "kria-k26-devboard"
        (path ""
          (reference "#PWR0118") (unit 1)
        )
      )
    )
  )

  (symbol (lib_id "kria-k26-devboard:R_11k_0402") (at 184.785 132.08 270) (unit 1)
    (in_bom yes) (on_board yes) (dnp no) (fields_autoplaced)
    (property "Reference" "R72" (at 186.69 133.35 90)
      (effects (font (size 1.524 1.524)) (justify left))
    )
    (property "Value" "R_11k_0402" (at 180.975 132.08 0)
      (effects (font (size 1.27 1.27) (thickness 0.15)) (justify left bottom) hide)
    )
    (property "Footprint" "kria-k26-devboard-footprints:R_0402_1005Metric" (at 189.865 137.16 0)
      (effects (font (size 1.27 1.27) (thickness 0.15)) (justify left bottom) hide)
    )
    (property "Datasheet" "https://www.bourns.com/docs/product-datasheets/cr.pdf" (at 184.785 132.08 0)
      (effects (font (size 1.27 1.27) (thickness 0.15)) (justify left bottom) hide)
    )
    (property "Manufacturer" "Bourns" (at 194.945 137.16 0)
      (effects (font (size 1.27 1.27) (thickness 0.15)) (justify left bottom) hide)
    )
    (property "MPN" "CR0402-FX-1102GLF" (at 192.405 137.16 0)
      (effects (font (size 1.27 1.27) (thickness 0.15)) (justify left bottom) hide)
    )
    (property "Val" "11k" (at 186.69 136.5249 90)
      (effects (font (size 1.27 1.27) (thickness 0.15)) (justify left))
    )
    (property "License" "Apache-2.0" (at 159.385 152.4 0)
      (effects (font (size 1.27 1.27) (thickness 0.15)) (justify left bottom) hide)
    )
    (property "Author" "Antmicro" (at 156.845 152.4 0)
      (effects (font (size 1.27 1.27) (thickness 0.15)) (justify left bottom) hide)
    )
    (property "Tolerance" "1%" (at 174.625 152.4 0)
      (effects (font (size 1.27 1.27)) (justify left bottom) hide)
    )
    (pin "1")
    (pin "2")
    (instances
      (project "kria-k26-devboard"
        (path ""
          (reference "R72") (unit 1)
        )
      )
    )
  )

  (symbol (lib_id "kria-k26-devboard:R_4k7_0402") (at 133.35 123.19 0) (mirror y) (unit 1)
    (in_bom yes) (on_board yes) (dnp no)
    (property "Reference" "R73" (at 126.365 121.92 0)
      (effects (font (size 1.524 1.524)))
    )
    (property "Value" "R_4k7_0402" (at 133.35 127 0)
      (effects (font (size 1.27 1.27) (thickness 0.15)) (justify left bottom) hide)
    )
    (property "Footprint" "kria-k26-devboard-footprints:R_0402_1005Metric" (at 128.27 118.11 0)
      (effects (font (size 1.27 1.27) (thickness 0.15)) (justify left bottom) hide)
    )
    (property "Datasheet" "https://www.bourns.com/docs/product-datasheets/cr.pdf" (at 133.35 123.19 0)
      (effects (font (size 1.27 1.27) (thickness 0.15)) (justify left bottom) hide)
    )
    (property "Manufacturer" "Bourns" (at 128.27 113.03 0)
      (effects (font (size 1.27 1.27) (thickness 0.15)) (justify left bottom) hide)
    )
    (property "MPN" "CR0402-FX-4701GLF" (at 128.27 115.57 0)
      (effects (font (size 1.27 1.27) (thickness 0.15)) (justify left bottom) hide)
    )
    (property "Val" "4k7" (at 134.62 121.92 0)
      (effects (font (size 1.27 1.27) (thickness 0.15)))
    )
    (property "License" "Apache-2.0" (at 113.03 148.59 0)
      (effects (font (size 1.27 1.27) (thickness 0.15)) (justify left bottom) hide)
    )
    (property "Author" "Antmicro" (at 113.03 151.13 0)
      (effects (font (size 1.27 1.27) (thickness 0.15)) (justify left bottom) hide)
    )
    (property "Tolerance" "1%" (at 113.03 133.35 0)
      (effects (font (size 1.27 1.27)) (justify left bottom) hide)
    )
    (pin "1")
    (pin "2")
    (instances
      (project "kria-k26-devboard"
        (path ""
          (reference "R73") (unit 1)
        )
      )
    )
  )

  (symbol (lib_id "kria-k26-devboard:R_4k7_0402") (at 133.35 128.27 0) (mirror y) (unit 1)
    (in_bom yes) (on_board yes) (dnp no)
    (property "Reference" "R74" (at 126.365 127 0)
      (effects (font (size 1.524 1.524)))
    )
    (property "Value" "R_4k7_0402" (at 133.35 132.08 0)
      (effects (font (size 1.27 1.27) (thickness 0.15)) (justify left bottom) hide)
    )
    (property "Footprint" "kria-k26-devboard-footprints:R_0402_1005Metric" (at 128.27 123.19 0)
      (effects (font (size 1.27 1.27) (thickness 0.15)) (justify left bottom) hide)
    )
    (property "Datasheet" "https://www.bourns.com/docs/product-datasheets/cr.pdf" (at 133.35 128.27 0)
      (effects (font (size 1.27 1.27) (thickness 0.15)) (justify left bottom) hide)
    )
    (property "Manufacturer" "Bourns" (at 128.27 118.11 0)
      (effects (font (size 1.27 1.27) (thickness 0.15)) (justify left bottom) hide)
    )
    (property "MPN" "CR0402-FX-4701GLF" (at 128.27 120.65 0)
      (effects (font (size 1.27 1.27) (thickness 0.15)) (justify left bottom) hide)
    )
    (property "Val" "4k7" (at 134.62 127 0)
      (effects (font (size 1.27 1.27) (thickness 0.15)))
    )
    (property "License" "Apache-2.0" (at 113.03 153.67 0)
      (effects (font (size 1.27 1.27) (thickness 0.15)) (justify left bottom) hide)
    )
    (property "Author" "Antmicro" (at 113.03 156.21 0)
      (effects (font (size 1.27 1.27) (thickness 0.15)) (justify left bottom) hide)
    )
    (property "Tolerance" "1%" (at 113.03 138.43 0)
      (effects (font (size 1.27 1.27)) (justify left bottom) hide)
    )
    (pin "1")
    (pin "2")
    (instances
      (project "kria-k26-devboard"
        (path ""
          (reference "R74") (unit 1)
        )
      )
    )
  )

  (symbol (lib_id "kria-k26-devboard:R_4k7_0402") (at 133.35 130.81 0) (mirror y) (unit 1)
    (in_bom yes) (on_board yes) (dnp no)
    (property "Reference" "R75" (at 126.365 129.54 0)
      (effects (font (size 1.524 1.524)))
    )
    (property "Value" "R_4k7_0402" (at 133.35 134.62 0)
      (effects (font (size 1.27 1.27) (thickness 0.15)) (justify left bottom) hide)
    )
    (property "Footprint" "kria-k26-devboard-footprints:R_0402_1005Metric" (at 128.27 125.73 0)
      (effects (font (size 1.27 1.27) (thickness 0.15)) (justify left bottom) hide)
    )
    (property "Datasheet" "https://www.bourns.com/docs/product-datasheets/cr.pdf" (at 133.35 130.81 0)
      (effects (font (size 1.27 1.27) (thickness 0.15)) (justify left bottom) hide)
    )
    (property "Manufacturer" "Bourns" (at 128.27 120.65 0)
      (effects (font (size 1.27 1.27) (thickness 0.15)) (justify left bottom) hide)
    )
    (property "MPN" "CR0402-FX-4701GLF" (at 128.27 123.19 0)
      (effects (font (size 1.27 1.27) (thickness 0.15)) (justify left bottom) hide)
    )
    (property "Val" "4k7" (at 134.62 129.54 0)
      (effects (font (size 1.27 1.27) (thickness 0.15)))
    )
    (property "License" "Apache-2.0" (at 113.03 156.21 0)
      (effects (font (size 1.27 1.27) (thickness 0.15)) (justify left bottom) hide)
    )
    (property "Author" "Antmicro" (at 113.03 158.75 0)
      (effects (font (size 1.27 1.27) (thickness 0.15)) (justify left bottom) hide)
    )
    (property "Tolerance" "1%" (at 113.03 140.97 0)
      (effects (font (size 1.27 1.27)) (justify left bottom) hide)
    )
    (pin "1")
    (pin "2")
    (instances
      (project "kria-k26-devboard"
        (path ""
          (reference "R75") (unit 1)
        )
      )
    )
  )

  (symbol (lib_id "kria-k26-devboard:Bus_RJ45_5-2337992-8") (at 250.19 78.74 0) (unit 1)
    (in_bom yes) (on_board yes) (dnp no)
    (property "Reference" "J5" (at 260.985 71.12 0)
      (effects (font (size 1.524 1.524)))
    )
    (property "Value" "Bus_RJ45_5-2337992-8" (at 260.985 73.66 0)
      (effects (font (size 1.27 1.27) (thickness 0.15)) hide)
    )
    (property "Footprint" "kria-k26-devboard-footprints:RJ45_5-2337992-8_Horizontal" (at 300.99 130.81 0)
      (effects (font (size 1.27 1.27) (thickness 0.15)) (justify left bottom) hide)
    )
    (property "Datasheet" "https://www.te.com/commerce/DocumentDelivery/DDEController?Action=showdoc&DocId=Customer+Drawing%7F5-2337992-8%7FA%7Fpdf%7FEnglish%7FENG_CD_5-2337992-8_A.pdf%7F5-2337992-8" (at 287.02 82.55 0)
      (effects (font (size 1.27 1.27) (thickness 0.15)) (justify left bottom) hide)
    )
    (property "MPN" "5-2337992-8" (at 260.985 73.66 0)
      (effects (font (size 1.27 1.27) (thickness 0.15)))
    )
    (property "Manufacturer" "TE Connectivity" (at 300.99 75.5396 0)
      (effects (font (size 1.27 1.27) (thickness 0.15)) (justify left bottom) hide)
    )
    (property "Author" "Antmicro" (at 285.75 96.52 0)
      (effects (font (size 1.27 1.27) (thickness 0.15)) (justify left bottom) hide)
    )
    (property "License" "Apache-2.0" (at 285.75 99.06 0)
      (effects (font (size 1.27 1.27) (thickness 0.15)) (justify left bottom) hide)
    )
    (property "VSD_Class" "Ethernet" (at 285.75 101.6 0)
      (effects (font (size 1.27 1.27)) (justify left bottom) hide)
    )
    (pin "1")
    (pin "10")
    (pin "11")
    (pin "12")
    (pin "13")
    (pin "14")
    (pin "15")
    (pin "16")
    (pin "17")
    (pin "18")
    (pin "19")
    (pin "2")
    (pin "20")
    (pin "3")
    (pin "4")
    (pin "5")
    (pin "6")
    (pin "7")
    (pin "8")
    (pin "9")
    (instances
      (project "kria-k26-devboard"
        (path ""
          (reference "J5") (unit 1)
        )
      )
    )
  )

  (symbol (lib_id "kria-k26-devboard:R_330R_0402") (at 296.545 87.63 270) (unit 1)
    (in_bom yes) (on_board yes) (dnp no) (fields_autoplaced)
    (property "Reference" "R78" (at 299.085 88.9 90)
      (effects (font (size 1.524 1.524)) (justify left))
    )
    (property "Value" "R_330R_0402" (at 292.735 87.63 0)
      (effects (font (size 1.27 1.27) (thickness 0.15)) (justify left bottom) hide)
    )
    (property "Footprint" "kria-k26-devboard-footprints:R_0402_1005Metric" (at 301.625 92.71 0)
      (effects (font (size 1.27 1.27) (thickness 0.15)) (justify left bottom) hide)
    )
    (property "Datasheet" "https://www.bourns.com/docs/product-datasheets/cr.pdf" (at 296.545 87.63 0)
      (effects (font (size 1.27 1.27) (thickness 0.15)) (justify left bottom) hide)
    )
    (property "Manufacturer" "Bourns" (at 306.705 92.71 0)
      (effects (font (size 1.27 1.27) (thickness 0.15)) (justify left bottom) hide)
    )
    (property "MPN" "CR0402-FX-3300GLF" (at 304.165 92.71 0)
      (effects (font (size 1.27 1.27) (thickness 0.15)) (justify left bottom) hide)
    )
    (property "Val" "330R" (at 299.085 92.0749 90)
      (effects (font (size 1.27 1.27) (thickness 0.15)) (justify left))
    )
    (property "License" "Apache-2.0" (at 271.145 107.95 0)
      (effects (font (size 1.27 1.27) (thickness 0.15)) (justify left bottom) hide)
    )
    (property "Author" "Antmicro" (at 268.605 107.95 0)
      (effects (font (size 1.27 1.27) (thickness 0.15)) (justify left bottom) hide)
    )
    (property "Tolerance" "1%" (at 286.385 107.95 0)
      (effects (font (size 1.27 1.27)) (justify left bottom) hide)
    )
    (pin "1")
    (pin "2")
    (instances
      (project "kria-k26-devboard"
        (path ""
          (reference "R78") (unit 1)
        )
      )
    )
  )

  (symbol (lib_id "kria-k26-devboard:R_330R_0402") (at 287.02 87.63 270) (unit 1)
    (in_bom yes) (on_board yes) (dnp no) (fields_autoplaced)
    (property "Reference" "R77" (at 289.56 88.9 90)
      (effects (font (size 1.524 1.524)) (justify left))
    )
    (property "Value" "R_330R_0402" (at 283.21 87.63 0)
      (effects (font (size 1.27 1.27) (thickness 0.15)) (justify left bottom) hide)
    )
    (property "Footprint" "kria-k26-devboard-footprints:R_0402_1005Metric" (at 292.1 92.71 0)
      (effects (font (size 1.27 1.27) (thickness 0.15)) (justify left bottom) hide)
    )
    (property "Datasheet" "https://www.bourns.com/docs/product-datasheets/cr.pdf" (at 287.02 87.63 0)
      (effects (font (size 1.27 1.27) (thickness 0.15)) (justify left bottom) hide)
    )
    (property "Manufacturer" "Bourns" (at 297.18 92.71 0)
      (effects (font (size 1.27 1.27) (thickness 0.15)) (justify left bottom) hide)
    )
    (property "MPN" "CR0402-FX-3300GLF" (at 294.64 92.71 0)
      (effects (font (size 1.27 1.27) (thickness 0.15)) (justify left bottom) hide)
    )
    (property "Val" "330R" (at 289.56 92.0749 90)
      (effects (font (size 1.27 1.27) (thickness 0.15)) (justify left))
    )
    (property "License" "Apache-2.0" (at 261.62 107.95 0)
      (effects (font (size 1.27 1.27) (thickness 0.15)) (justify left bottom) hide)
    )
    (property "Author" "Antmicro" (at 259.08 107.95 0)
      (effects (font (size 1.27 1.27) (thickness 0.15)) (justify left bottom) hide)
    )
    (property "Tolerance" "1%" (at 276.86 107.95 0)
      (effects (font (size 1.27 1.27)) (justify left bottom) hide)
    )
    (pin "1")
    (pin "2")
    (instances
      (project "kria-k26-devboard"
        (path ""
          (reference "R77") (unit 1)
        )
      )
    )
  )

  (symbol (lib_id "kria-k26-devboard:DP83867CR_VQFN") (at 138.43 68.58 0) (unit 1)
    (in_bom yes) (on_board yes) (dnp no) (fields_autoplaced)
    (property "Reference" "U30" (at 160.655 59.69 0)
      (effects (font (size 1.524 1.524)))
    )
    (property "Value" "DP83867CR_VQFN" (at 209.55 74.93 0)
      (effects (font (size 1.27 1.27) (thickness 0.15)) (justify left bottom) hide)
    )
    (property "Footprint" "kria-k26-devboard-footprints:QFN-48-1EP_7x7mm" (at 209.55 77.47 0)
      (effects (font (size 1.27 1.27) (thickness 0.15)) (justify left bottom) hide)
    )
    (property "Datasheet" "https://www.ti.com/lit/ds/symlink/dp83867ir.pdf?ts=1647232328899&ref_url=https%253A%252F%252Fwww.ti.com%252Fproduct%252FDP83867IR" (at 209.55 80.01 0)
      (effects (font (size 1.27 1.27) (thickness 0.15)) (justify left bottom) hide)
    )
    (property "Manufacturer" "Texas Instruments" (at 209.55 82.55 0)
      (effects (font (size 1.27 1.27) (thickness 0.15)) (justify left bottom) hide)
    )
    (property "MPN" "DP83867CRRGZR" (at 160.655 63.5 0)
      (effects (font (size 1.27 1.27) (thickness 0.15)))
    )
    (property "Author" "Antmicro" (at 209.55 87.63 0)
      (effects (font (size 1.27 1.27) (thickness 0.15)) (justify left bottom) hide)
    )
    (property "License" "Apache-2.0" (at 209.55 90.17 0)
      (effects (font (size 1.27 1.27) (thickness 0.15)) (justify left bottom) hide)
    )
    (pin "1")
    (pin "10")
    (pin "11")
    (pin "12")
    (pin "13")
    (pin "14")
    (pin "15")
    (pin "16")
    (pin "17")
    (pin "18")
    (pin "19")
    (pin "2")
    (pin "20")
    (pin "21")
    (pin "22")
    (pin "23")
    (pin "24")
    (pin "25")
    (pin "26")
    (pin "27")
    (pin "28")
    (pin "29")
    (pin "3")
    (pin "30")
    (pin "31")
    (pin "32")
    (pin "33")
    (pin "34")
    (pin "35")
    (pin "36")
    (pin "37")
    (pin "38")
    (pin "39")
    (pin "4")
    (pin "40")
    (pin "41")
    (pin "42")
    (pin "43")
    (pin "44")
    (pin "45")
    (pin "46")
    (pin "47")
    (pin "48")
    (pin "49")
    (pin "5")
    (pin "6")
    (pin "7")
    (pin "8")
    (pin "9")
    (instances
      (project "kria-k26-devboard"
        (path ""
          (reference "U30") (unit 1)
        )
      )
    )
  )

  (symbol (lib_id "kria-k26-devboard:C_10u_0603") (at 38.1 80.645 270) (unit 1)
    (in_bom yes) (on_board yes) (dnp no) (fields_autoplaced)
    (property "Reference" "C90" (at 40.64 81.9213 90)
      (effects (font (size 1.524 1.524)) (justify left))
    )
    (property "Value" "C_10u_0603" (at 34.29 80.645 0)
      (effects (font (size 1.27 1.27) (thickness 0.15)) (justify left bottom) hide)
    )
    (property "Footprint" "kria-k26-devboard-footprints:C_0603_1608Metric" (at 43.18 85.725 0)
      (effects (font (size 1.27 1.27) (thickness 0.15)) (justify left bottom) hide)
    )
    (property "Datasheet" " " (at 38.1 80.645 0)
      (effects (font (size 1.27 1.27) (thickness 0.15)) (justify left bottom) hide)
    )
    (property "Manufacturer" "Murata" (at 48.26 85.725 0)
      (effects (font (size 1.27 1.27) (thickness 0.15)) (justify left bottom) hide)
    )
    (property "MPN" "GRM188R61A106KE69D" (at 45.72 85.725 0)
      (effects (font (size 1.27 1.27) (thickness 0.15)) (justify left bottom) hide)
    )
    (property "Val" "10u" (at 40.64 85.0962 90)
      (effects (font (size 1.27 1.27) (thickness 0.15)) (justify left))
    )
    (property "License" "Apache-2.0" (at 15.24 100.965 0)
      (effects (font (size 1.27 1.27) (thickness 0.15)) (justify left bottom) hide)
    )
    (property "Author" "Antmicro" (at 12.7 100.965 0)
      (effects (font (size 1.27 1.27) (thickness 0.15)) (justify left bottom) hide)
    )
    (property "Voltage" "" (at 10.16 100.965 0)
      (effects (font (size 1.27 1.27)) (justify left bottom) hide)
    )
    (pin "1")
    (pin "2")
    (instances
      (project "kria-k26-devboard"
        (path ""
          (reference "C90") (unit 1)
        )
      )
    )
  )

  (symbol (lib_id "kria-k26-devboard:C_10n_0402") (at 48.26 80.645 270) (unit 1)
    (in_bom yes) (on_board yes) (dnp no) (fields_autoplaced)
    (property "Reference" "C92" (at 50.8 81.9213 90)
      (effects (font (size 1.524 1.524)) (justify left))
    )
    (property "Value" "C_10n_0402" (at 44.45 80.645 0)
      (effects (font (size 1.27 1.27) (thickness 0.15)) (justify left bottom) hide)
    )
    (property "Footprint" "kria-k26-devboard-footprints:C_0402_1005Metric" (at 53.34 85.725 0)
      (effects (font (size 1.27 1.27) (thickness 0.15)) (justify left bottom) hide)
    )
    (property "Datasheet" "https://search.murata.co.jp/Ceramy/image/img/A01X/G101/ENG/GRM155R71H103KA88-01.pdf" (at 48.26 80.645 0)
      (effects (font (size 1.27 1.27) (thickness 0.15)) (justify left bottom) hide)
    )
    (property "Manufacturer" "Murata" (at 58.42 85.725 0)
      (effects (font (size 1.27 1.27) (thickness 0.15)) (justify left bottom) hide)
    )
    (property "MPN" "GRM155R71H103KA88D" (at 55.88 85.725 0)
      (effects (font (size 1.27 1.27) (thickness 0.15)) (justify left bottom) hide)
    )
    (property "Val" "10n" (at 50.8 85.0962 90)
      (effects (font (size 1.27 1.27) (thickness 0.15)) (justify left))
    )
    (property "License" "Apache-2.0" (at 25.4 100.965 0)
      (effects (font (size 1.27 1.27) (thickness 0.15)) (justify left bottom) hide)
    )
    (property "Author" "Antmicro" (at 22.86 100.965 0)
      (effects (font (size 1.27 1.27) (thickness 0.15)) (justify left bottom) hide)
    )
    (property "Voltage" "50V" (at 20.32 100.965 0)
      (effects (font (size 1.27 1.27)) (justify left bottom) hide)
    )
    (property "Dielectric" "X7R" (at 17.78 100.965 0)
      (effects (font (size 1.27 1.27)) (justify left bottom) hide)
    )
    (pin "1")
    (pin "2")
    (instances
      (project "kria-k26-devboard"
        (path ""
          (reference "C92") (unit 1)
        )
      )
    )
  )

  (symbol (lib_id "kria-k26-devboard:C_100n_0402") (at 71.12 80.01 270) (unit 1)
    (in_bom yes) (on_board yes) (dnp no) (fields_autoplaced)
    (property "Reference" "C100" (at 73.66 81.2863 90)
      (effects (font (size 1.524 1.524)) (justify left))
    )
    (property "Value" "C_100n_0402" (at 67.31 80.01 0)
      (effects (font (size 1.27 1.27) (thickness 0.15)) (justify left bottom) hide)
    )
    (property "Footprint" "kria-k26-devboard-footprints:C_0402_1005Metric" (at 76.2 85.09 0)
      (effects (font (size 1.27 1.27) (thickness 0.15)) (justify left bottom) hide)
    )
    (property "Datasheet" "https://search.murata.co.jp/Ceramy/image/img/A01X/G101/ENG/GRM155R61H104KE14-01.pdf" (at 71.12 80.01 0)
      (effects (font (size 1.27 1.27) (thickness 0.15)) (justify left bottom) hide)
    )
    (property "Manufacturer" "Murata" (at 81.28 85.09 0)
      (effects (font (size 1.27 1.27) (thickness 0.15)) (justify left bottom) hide)
    )
    (property "MPN" "GRM155R61H104KE14D" (at 78.74 85.09 0)
      (effects (font (size 1.27 1.27) (thickness 0.15)) (justify left bottom) hide)
    )
    (property "Val" "100n" (at 73.66 84.4612 90)
      (effects (font (size 1.27 1.27) (thickness 0.15)) (justify left))
    )
    (property "License" "Apache-2.0" (at 48.26 100.33 0)
      (effects (font (size 1.27 1.27) (thickness 0.15)) (justify left bottom) hide)
    )
    (property "Author" "Antmicro" (at 45.72 100.33 0)
      (effects (font (size 1.27 1.27) (thickness 0.15)) (justify left bottom) hide)
    )
    (property "Voltage" "50V" (at 43.18 100.33 0)
      (effects (font (size 1.27 1.27)) (justify left bottom) hide)
    )
    (property "Dielectric" "X5R" (at 40.64 100.33 0)
      (effects (font (size 1.27 1.27)) (justify left bottom) hide)
    )
    (pin "1")
    (pin "2")
    (instances
      (project "kria-k26-devboard"
        (path ""
          (reference "C100") (unit 1)
        )
      )
    )
  )

  (symbol (lib_id "kria-k26-devboard:C_1u_0402") (at 60.96 80.01 270) (unit 1)
    (in_bom yes) (on_board yes) (dnp no) (fields_autoplaced)
    (property "Reference" "C95" (at 63.5 81.2863 90)
      (effects (font (size 1.524 1.524)) (justify left))
    )
    (property "Value" "C_1u_0402" (at 57.15 80.01 0)
      (effects (font (size 1.27 1.27) (thickness 0.15)) (justify left bottom) hide)
    )
    (property "Footprint" "kria-k26-devboard-footprints:C_0402_1005Metric" (at 66.04 85.09 0)
      (effects (font (size 1.27 1.27) (thickness 0.15)) (justify left bottom) hide)
    )
    (property "Datasheet" " " (at 60.96 80.01 0)
      (effects (font (size 1.27 1.27) (thickness 0.15)) (justify left bottom) hide)
    )
    (property "Manufacturer" "TDK" (at 71.12 85.09 0)
      (effects (font (size 1.27 1.27) (thickness 0.15)) (justify left bottom) hide)
    )
    (property "MPN" "C1005X6S1A105K050BC" (at 68.58 85.09 0)
      (effects (font (size 1.27 1.27) (thickness 0.15)) (justify left bottom) hide)
    )
    (property "Val" "1u" (at 63.5 84.4612 90)
      (effects (font (size 1.27 1.27) (thickness 0.15)) (justify left))
    )
    (property "License" "Apache-2.0" (at 38.1 100.33 0)
      (effects (font (size 1.27 1.27) (thickness 0.15)) (justify left bottom) hide)
    )
    (property "Author" "Antmicro" (at 35.56 100.33 0)
      (effects (font (size 1.27 1.27) (thickness 0.15)) (justify left bottom) hide)
    )
    (property "Voltage" "" (at 33.02 100.33 0)
      (effects (font (size 1.27 1.27)) (justify left bottom) hide)
    )
    (property "Dielectric" "" (at 30.48 100.33 0)
      (effects (font (size 1.27 1.27)) (justify left bottom) hide)
    )
    (pin "1")
    (pin "2")
    (instances
      (project "kria-k26-devboard"
        (path ""
          (reference "C95") (unit 1)
        )
      )
    )
  )

  (symbol (lib_id "kria-k26-devboard:GND") (at 48.26 85.725 0) (unit 1)
    (in_bom yes) (on_board yes) (dnp no) (fields_autoplaced)
    (property "Reference" "#PWR0106" (at 48.26 92.075 0)
      (effects (font (size 1.27 1.27)) hide)
    )
    (property "Value" "GND" (at 48.26 90.805 0)
      (effects (font (size 1.27 1.27)))
    )
    (property "Footprint" "" (at 57.15 93.345 0)
      (effects (font (size 1.27 1.27) (thickness 0.15)) (justify left bottom) hide)
    )
    (property "Datasheet" "" (at 57.15 98.425 0)
      (effects (font (size 1.27 1.27) (thickness 0.15)) (justify left bottom) hide)
    )
    (property "Author" "Antmicro" (at 57.15 93.345 0)
      (effects (font (size 1.27 1.27) (thickness 0.15)) (justify left bottom) hide)
    )
    (property "License" "Apache-2.0" (at 57.15 95.885 0)
      (effects (font (size 1.27 1.27) (thickness 0.15)) (justify left bottom) hide)
    )
    (pin "1")
    (instances
      (project "kria-k26-devboard"
        (path ""
          (reference "#PWR0106") (unit 1)
        )
      )
    )
  )

  (symbol (lib_id "kria-k26-devboard:C_100n_0402") (at 71.12 62.23 270) (unit 1)
    (in_bom yes) (on_board yes) (dnp no) (fields_autoplaced)
    (property "Reference" "C99" (at 73.66 63.5063 90)
      (effects (font (size 1.524 1.524)) (justify left))
    )
    (property "Value" "C_100n_0402" (at 67.31 62.23 0)
      (effects (font (size 1.27 1.27) (thickness 0.15)) (justify left bottom) hide)
    )
    (property "Footprint" "kria-k26-devboard-footprints:C_0402_1005Metric" (at 76.2 67.31 0)
      (effects (font (size 1.27 1.27) (thickness 0.15)) (justify left bottom) hide)
    )
    (property "Datasheet" "https://search.murata.co.jp/Ceramy/image/img/A01X/G101/ENG/GRM155R61H104KE14-01.pdf" (at 71.12 62.23 0)
      (effects (font (size 1.27 1.27) (thickness 0.15)) (justify left bottom) hide)
    )
    (property "Manufacturer" "Murata" (at 81.28 67.31 0)
      (effects (font (size 1.27 1.27) (thickness 0.15)) (justify left bottom) hide)
    )
    (property "MPN" "GRM155R61H104KE14D" (at 78.74 67.31 0)
      (effects (font (size 1.27 1.27) (thickness 0.15)) (justify left bottom) hide)
    )
    (property "Val" "100n" (at 73.66 66.6812 90)
      (effects (font (size 1.27 1.27) (thickness 0.15)) (justify left))
    )
    (property "License" "Apache-2.0" (at 48.26 82.55 0)
      (effects (font (size 1.27 1.27) (thickness 0.15)) (justify left bottom) hide)
    )
    (property "Author" "Antmicro" (at 45.72 82.55 0)
      (effects (font (size 1.27 1.27) (thickness 0.15)) (justify left bottom) hide)
    )
    (property "Voltage" "50V" (at 43.18 82.55 0)
      (effects (font (size 1.27 1.27)) (justify left bottom) hide)
    )
    (property "Dielectric" "X5R" (at 40.64 82.55 0)
      (effects (font (size 1.27 1.27)) (justify left bottom) hide)
    )
    (pin "1")
    (pin "2")
    (instances
      (project "kria-k26-devboard"
        (path ""
          (reference "C99") (unit 1)
        )
      )
    )
  )

  (symbol (lib_id "kria-k26-devboard:C_1u_0402") (at 60.96 62.23 270) (unit 1)
    (in_bom yes) (on_board yes) (dnp no) (fields_autoplaced)
    (property "Reference" "C94" (at 63.5 63.5063 90)
      (effects (font (size 1.524 1.524)) (justify left))
    )
    (property "Value" "C_1u_0402" (at 57.15 62.23 0)
      (effects (font (size 1.27 1.27) (thickness 0.15)) (justify left bottom) hide)
    )
    (property "Footprint" "kria-k26-devboard-footprints:C_0402_1005Metric" (at 66.04 67.31 0)
      (effects (font (size 1.27 1.27) (thickness 0.15)) (justify left bottom) hide)
    )
    (property "Datasheet" " " (at 60.96 62.23 0)
      (effects (font (size 1.27 1.27) (thickness 0.15)) (justify left bottom) hide)
    )
    (property "Manufacturer" "TDK" (at 71.12 67.31 0)
      (effects (font (size 1.27 1.27) (thickness 0.15)) (justify left bottom) hide)
    )
    (property "MPN" "C1005X6S1A105K050BC" (at 68.58 67.31 0)
      (effects (font (size 1.27 1.27) (thickness 0.15)) (justify left bottom) hide)
    )
    (property "Val" "1u" (at 63.5 66.6812 90)
      (effects (font (size 1.27 1.27) (thickness 0.15)) (justify left))
    )
    (property "License" "Apache-2.0" (at 38.1 82.55 0)
      (effects (font (size 1.27 1.27) (thickness 0.15)) (justify left bottom) hide)
    )
    (property "Author" "Antmicro" (at 35.56 82.55 0)
      (effects (font (size 1.27 1.27) (thickness 0.15)) (justify left bottom) hide)
    )
    (property "Voltage" "" (at 33.02 82.55 0)
      (effects (font (size 1.27 1.27)) (justify left bottom) hide)
    )
    (property "Dielectric" "" (at 30.48 82.55 0)
      (effects (font (size 1.27 1.27)) (justify left bottom) hide)
    )
    (pin "1")
    (pin "2")
    (instances
      (project "kria-k26-devboard"
        (path ""
          (reference "C94") (unit 1)
        )
      )
    )
  )

  (symbol (lib_id "kria-k26-devboard:C_100n_0402") (at 71.12 99.06 270) (unit 1)
    (in_bom yes) (on_board yes) (dnp no) (fields_autoplaced)
    (property "Reference" "C101" (at 73.66 100.3363 90)
      (effects (font (size 1.524 1.524)) (justify left))
    )
    (property "Value" "C_100n_0402" (at 67.31 99.06 0)
      (effects (font (size 1.27 1.27) (thickness 0.15)) (justify left bottom) hide)
    )
    (property "Footprint" "kria-k26-devboard-footprints:C_0402_1005Metric" (at 76.2 104.14 0)
      (effects (font (size 1.27 1.27) (thickness 0.15)) (justify left bottom) hide)
    )
    (property "Datasheet" "https://search.murata.co.jp/Ceramy/image/img/A01X/G101/ENG/GRM155R61H104KE14-01.pdf" (at 71.12 99.06 0)
      (effects (font (size 1.27 1.27) (thickness 0.15)) (justify left bottom) hide)
    )
    (property "Manufacturer" "Murata" (at 81.28 104.14 0)
      (effects (font (size 1.27 1.27) (thickness 0.15)) (justify left bottom) hide)
    )
    (property "MPN" "GRM155R61H104KE14D" (at 78.74 104.14 0)
      (effects (font (size 1.27 1.27) (thickness 0.15)) (justify left bottom) hide)
    )
    (property "Val" "100n" (at 73.66 103.5112 90)
      (effects (font (size 1.27 1.27) (thickness 0.15)) (justify left))
    )
    (property "License" "Apache-2.0" (at 48.26 119.38 0)
      (effects (font (size 1.27 1.27) (thickness 0.15)) (justify left bottom) hide)
    )
    (property "Author" "Antmicro" (at 45.72 119.38 0)
      (effects (font (size 1.27 1.27) (thickness 0.15)) (justify left bottom) hide)
    )
    (property "Voltage" "50V" (at 43.18 119.38 0)
      (effects (font (size 1.27 1.27)) (justify left bottom) hide)
    )
    (property "Dielectric" "X5R" (at 40.64 119.38 0)
      (effects (font (size 1.27 1.27)) (justify left bottom) hide)
    )
    (pin "1")
    (pin "2")
    (instances
      (project "kria-k26-devboard"
        (path ""
          (reference "C101") (unit 1)
        )
      )
    )
  )

  (symbol (lib_id "kria-k26-devboard:C_1u_0402") (at 60.96 99.06 270) (unit 1)
    (in_bom yes) (on_board yes) (dnp no) (fields_autoplaced)
    (property "Reference" "C96" (at 63.5 100.3363 90)
      (effects (font (size 1.524 1.524)) (justify left))
    )
    (property "Value" "C_1u_0402" (at 57.15 99.06 0)
      (effects (font (size 1.27 1.27) (thickness 0.15)) (justify left bottom) hide)
    )
    (property "Footprint" "kria-k26-devboard-footprints:C_0402_1005Metric" (at 66.04 104.14 0)
      (effects (font (size 1.27 1.27) (thickness 0.15)) (justify left bottom) hide)
    )
    (property "Datasheet" " " (at 60.96 99.06 0)
      (effects (font (size 1.27 1.27) (thickness 0.15)) (justify left bottom) hide)
    )
    (property "Manufacturer" "TDK" (at 71.12 104.14 0)
      (effects (font (size 1.27 1.27) (thickness 0.15)) (justify left bottom) hide)
    )
    (property "MPN" "C1005X6S1A105K050BC" (at 68.58 104.14 0)
      (effects (font (size 1.27 1.27) (thickness 0.15)) (justify left bottom) hide)
    )
    (property "Val" "1u" (at 63.5 103.5112 90)
      (effects (font (size 1.27 1.27) (thickness 0.15)) (justify left))
    )
    (property "License" "Apache-2.0" (at 38.1 119.38 0)
      (effects (font (size 1.27 1.27) (thickness 0.15)) (justify left bottom) hide)
    )
    (property "Author" "Antmicro" (at 35.56 119.38 0)
      (effects (font (size 1.27 1.27) (thickness 0.15)) (justify left bottom) hide)
    )
    (property "Voltage" "" (at 33.02 119.38 0)
      (effects (font (size 1.27 1.27)) (justify left bottom) hide)
    )
    (property "Dielectric" "" (at 30.48 119.38 0)
      (effects (font (size 1.27 1.27)) (justify left bottom) hide)
    )
    (pin "1")
    (pin "2")
    (instances
      (project "kria-k26-devboard"
        (path ""
          (reference "C96") (unit 1)
        )
      )
    )
  )

  (symbol (lib_id "kria-k26-devboard:C_10u_0603") (at 39.37 120.65 270) (unit 1)
    (in_bom yes) (on_board yes) (dnp no) (fields_autoplaced)
    (property "Reference" "C91" (at 42.545 121.9263 90)
      (effects (font (size 1.524 1.524)) (justify left))
    )
    (property "Value" "C_10u_0603" (at 35.56 120.65 0)
      (effects (font (size 1.27 1.27) (thickness 0.15)) (justify left bottom) hide)
    )
    (property "Footprint" "kria-k26-devboard-footprints:C_0603_1608Metric" (at 44.45 125.73 0)
      (effects (font (size 1.27 1.27) (thickness 0.15)) (justify left bottom) hide)
    )
    (property "Datasheet" " " (at 39.37 120.65 0)
      (effects (font (size 1.27 1.27) (thickness 0.15)) (justify left bottom) hide)
    )
    (property "Manufacturer" "Murata" (at 49.53 125.73 0)
      (effects (font (size 1.27 1.27) (thickness 0.15)) (justify left bottom) hide)
    )
    (property "MPN" "GRM188R61A106KE69D" (at 46.99 125.73 0)
      (effects (font (size 1.27 1.27) (thickness 0.15)) (justify left bottom) hide)
    )
    (property "Val" "10u" (at 42.545 125.1012 90)
      (effects (font (size 1.27 1.27) (thickness 0.15)) (justify left))
    )
    (property "License" "Apache-2.0" (at 16.51 140.97 0)
      (effects (font (size 1.27 1.27) (thickness 0.15)) (justify left bottom) hide)
    )
    (property "Author" "Antmicro" (at 13.97 140.97 0)
      (effects (font (size 1.27 1.27) (thickness 0.15)) (justify left bottom) hide)
    )
    (property "Voltage" "" (at 11.43 140.97 0)
      (effects (font (size 1.27 1.27)) (justify left bottom) hide)
    )
    (pin "1")
    (pin "2")
    (instances
      (project "kria-k26-devboard"
        (path ""
          (reference "C91") (unit 1)
        )
      )
    )
  )

  (symbol (lib_id "kria-k26-devboard:C_10n_0402") (at 49.53 120.65 270) (unit 1)
    (in_bom yes) (on_board yes) (dnp no) (fields_autoplaced)
    (property "Reference" "C93" (at 52.07 121.9263 90)
      (effects (font (size 1.524 1.524)) (justify left))
    )
    (property "Value" "C_10n_0402" (at 45.72 120.65 0)
      (effects (font (size 1.27 1.27) (thickness 0.15)) (justify left bottom) hide)
    )
    (property "Footprint" "kria-k26-devboard-footprints:C_0402_1005Metric" (at 54.61 125.73 0)
      (effects (font (size 1.27 1.27) (thickness 0.15)) (justify left bottom) hide)
    )
    (property "Datasheet" "https://search.murata.co.jp/Ceramy/image/img/A01X/G101/ENG/GRM155R71H103KA88-01.pdf" (at 49.53 120.65 0)
      (effects (font (size 1.27 1.27) (thickness 0.15)) (justify left bottom) hide)
    )
    (property "Manufacturer" "Murata" (at 59.69 125.73 0)
      (effects (font (size 1.27 1.27) (thickness 0.15)) (justify left bottom) hide)
    )
    (property "MPN" "GRM155R71H103KA88D" (at 57.15 125.73 0)
      (effects (font (size 1.27 1.27) (thickness 0.15)) (justify left bottom) hide)
    )
    (property "Val" "10n" (at 52.07 125.1012 90)
      (effects (font (size 1.27 1.27) (thickness 0.15)) (justify left))
    )
    (property "License" "Apache-2.0" (at 26.67 140.97 0)
      (effects (font (size 1.27 1.27) (thickness 0.15)) (justify left bottom) hide)
    )
    (property "Author" "Antmicro" (at 24.13 140.97 0)
      (effects (font (size 1.27 1.27) (thickness 0.15)) (justify left bottom) hide)
    )
    (property "Voltage" "50V" (at 21.59 140.97 0)
      (effects (font (size 1.27 1.27)) (justify left bottom) hide)
    )
    (property "Dielectric" "X7R" (at 19.05 140.97 0)
      (effects (font (size 1.27 1.27)) (justify left bottom) hide)
    )
    (pin "1")
    (pin "2")
    (instances
      (project "kria-k26-devboard"
        (path ""
          (reference "C93") (unit 1)
        )
      )
    )
  )

  (symbol (lib_id "kria-k26-devboard:C_100n_0402") (at 72.39 120.65 270) (unit 1)
    (in_bom yes) (on_board yes) (dnp no) (fields_autoplaced)
    (property "Reference" "C102" (at 74.93 121.9263 90)
      (effects (font (size 1.524 1.524)) (justify left))
    )
    (property "Value" "C_100n_0402" (at 68.58 120.65 0)
      (effects (font (size 1.27 1.27) (thickness 0.15)) (justify left bottom) hide)
    )
    (property "Footprint" "kria-k26-devboard-footprints:C_0402_1005Metric" (at 77.47 125.73 0)
      (effects (font (size 1.27 1.27) (thickness 0.15)) (justify left bottom) hide)
    )
    (property "Datasheet" "https://search.murata.co.jp/Ceramy/image/img/A01X/G101/ENG/GRM155R61H104KE14-01.pdf" (at 72.39 120.65 0)
      (effects (font (size 1.27 1.27) (thickness 0.15)) (justify left bottom) hide)
    )
    (property "Manufacturer" "Murata" (at 82.55 125.73 0)
      (effects (font (size 1.27 1.27) (thickness 0.15)) (justify left bottom) hide)
    )
    (property "MPN" "GRM155R61H104KE14D" (at 80.01 125.73 0)
      (effects (font (size 1.27 1.27) (thickness 0.15)) (justify left bottom) hide)
    )
    (property "Val" "100n" (at 74.93 125.1012 90)
      (effects (font (size 1.27 1.27) (thickness 0.15)) (justify left))
    )
    (property "License" "Apache-2.0" (at 49.53 140.97 0)
      (effects (font (size 1.27 1.27) (thickness 0.15)) (justify left bottom) hide)
    )
    (property "Author" "Antmicro" (at 46.99 140.97 0)
      (effects (font (size 1.27 1.27) (thickness 0.15)) (justify left bottom) hide)
    )
    (property "Voltage" "50V" (at 44.45 140.97 0)
      (effects (font (size 1.27 1.27)) (justify left bottom) hide)
    )
    (property "Dielectric" "X5R" (at 41.91 140.97 0)
      (effects (font (size 1.27 1.27)) (justify left bottom) hide)
    )
    (pin "1")
    (pin "2")
    (instances
      (project "kria-k26-devboard"
        (path ""
          (reference "C102") (unit 1)
        )
      )
    )
  )

  (symbol (lib_id "kria-k26-devboard:C_1u_0402") (at 62.23 120.65 270) (unit 1)
    (in_bom yes) (on_board yes) (dnp no) (fields_autoplaced)
    (property "Reference" "C97" (at 65.405 121.9263 90)
      (effects (font (size 1.524 1.524)) (justify left))
    )
    (property "Value" "C_1u_0402" (at 58.42 120.65 0)
      (effects (font (size 1.27 1.27) (thickness 0.15)) (justify left bottom) hide)
    )
    (property "Footprint" "kria-k26-devboard-footprints:C_0402_1005Metric" (at 67.31 125.73 0)
      (effects (font (size 1.27 1.27) (thickness 0.15)) (justify left bottom) hide)
    )
    (property "Datasheet" " " (at 62.23 120.65 0)
      (effects (font (size 1.27 1.27) (thickness 0.15)) (justify left bottom) hide)
    )
    (property "Manufacturer" "TDK" (at 72.39 125.73 0)
      (effects (font (size 1.27 1.27) (thickness 0.15)) (justify left bottom) hide)
    )
    (property "MPN" "C1005X6S1A105K050BC" (at 69.85 125.73 0)
      (effects (font (size 1.27 1.27) (thickness 0.15)) (justify left bottom) hide)
    )
    (property "Val" "1u" (at 65.405 125.1012 90)
      (effects (font (size 1.27 1.27) (thickness 0.15)) (justify left))
    )
    (property "License" "Apache-2.0" (at 39.37 140.97 0)
      (effects (font (size 1.27 1.27) (thickness 0.15)) (justify left bottom) hide)
    )
    (property "Author" "Antmicro" (at 36.83 140.97 0)
      (effects (font (size 1.27 1.27) (thickness 0.15)) (justify left bottom) hide)
    )
    (property "Voltage" "" (at 34.29 140.97 0)
      (effects (font (size 1.27 1.27)) (justify left bottom) hide)
    )
    (property "Dielectric" "" (at 31.75 140.97 0)
      (effects (font (size 1.27 1.27)) (justify left bottom) hide)
    )
    (pin "1")
    (pin "2")
    (instances
      (project "kria-k26-devboard"
        (path ""
          (reference "C97") (unit 1)
        )
      )
    )
  )

  (symbol (lib_id "kria-k26-devboard:C_100n_0402") (at 72.39 139.7 270) (unit 1)
    (in_bom yes) (on_board yes) (dnp no) (fields_autoplaced)
    (property "Reference" "C103" (at 74.93 140.9763 90)
      (effects (font (size 1.524 1.524)) (justify left))
    )
    (property "Value" "C_100n_0402" (at 68.58 139.7 0)
      (effects (font (size 1.27 1.27) (thickness 0.15)) (justify left bottom) hide)
    )
    (property "Footprint" "kria-k26-devboard-footprints:C_0402_1005Metric" (at 77.47 144.78 0)
      (effects (font (size 1.27 1.27) (thickness 0.15)) (justify left bottom) hide)
    )
    (property "Datasheet" "https://search.murata.co.jp/Ceramy/image/img/A01X/G101/ENG/GRM155R61H104KE14-01.pdf" (at 72.39 139.7 0)
      (effects (font (size 1.27 1.27) (thickness 0.15)) (justify left bottom) hide)
    )
    (property "Manufacturer" "Murata" (at 82.55 144.78 0)
      (effects (font (size 1.27 1.27) (thickness 0.15)) (justify left bottom) hide)
    )
    (property "MPN" "GRM155R61H104KE14D" (at 80.01 144.78 0)
      (effects (font (size 1.27 1.27) (thickness 0.15)) (justify left bottom) hide)
    )
    (property "Val" "100n" (at 74.93 144.1512 90)
      (effects (font (size 1.27 1.27) (thickness 0.15)) (justify left))
    )
    (property "License" "Apache-2.0" (at 49.53 160.02 0)
      (effects (font (size 1.27 1.27) (thickness 0.15)) (justify left bottom) hide)
    )
    (property "Author" "Antmicro" (at 46.99 160.02 0)
      (effects (font (size 1.27 1.27) (thickness 0.15)) (justify left bottom) hide)
    )
    (property "Voltage" "50V" (at 44.45 160.02 0)
      (effects (font (size 1.27 1.27)) (justify left bottom) hide)
    )
    (property "Dielectric" "X5R" (at 41.91 160.02 0)
      (effects (font (size 1.27 1.27)) (justify left bottom) hide)
    )
    (pin "1")
    (pin "2")
    (instances
      (project "kria-k26-devboard"
        (path ""
          (reference "C103") (unit 1)
        )
      )
    )
  )

  (symbol (lib_id "kria-k26-devboard:C_1u_0402") (at 62.23 139.7 270) (unit 1)
    (in_bom yes) (on_board yes) (dnp no) (fields_autoplaced)
    (property "Reference" "C98" (at 64.77 140.9763 90)
      (effects (font (size 1.524 1.524)) (justify left))
    )
    (property "Value" "C_1u_0402" (at 58.42 139.7 0)
      (effects (font (size 1.27 1.27) (thickness 0.15)) (justify left bottom) hide)
    )
    (property "Footprint" "kria-k26-devboard-footprints:C_0402_1005Metric" (at 67.31 144.78 0)
      (effects (font (size 1.27 1.27) (thickness 0.15)) (justify left bottom) hide)
    )
    (property "Datasheet" " " (at 62.23 139.7 0)
      (effects (font (size 1.27 1.27) (thickness 0.15)) (justify left bottom) hide)
    )
    (property "Manufacturer" "TDK" (at 72.39 144.78 0)
      (effects (font (size 1.27 1.27) (thickness 0.15)) (justify left bottom) hide)
    )
    (property "MPN" "C1005X6S1A105K050BC" (at 69.85 144.78 0)
      (effects (font (size 1.27 1.27) (thickness 0.15)) (justify left bottom) hide)
    )
    (property "Val" "1u" (at 64.77 144.1512 90)
      (effects (font (size 1.27 1.27) (thickness 0.15)) (justify left))
    )
    (property "License" "Apache-2.0" (at 39.37 160.02 0)
      (effects (font (size 1.27 1.27) (thickness 0.15)) (justify left bottom) hide)
    )
    (property "Author" "Antmicro" (at 36.83 160.02 0)
      (effects (font (size 1.27 1.27) (thickness 0.15)) (justify left bottom) hide)
    )
    (property "Voltage" "" (at 34.29 160.02 0)
      (effects (font (size 1.27 1.27)) (justify left bottom) hide)
    )
    (property "Dielectric" "" (at 31.75 160.02 0)
      (effects (font (size 1.27 1.27)) (justify left bottom) hide)
    )
    (pin "1")
    (pin "2")
    (instances
      (project "kria-k26-devboard"
        (path ""
          (reference "C98") (unit 1)
        )
      )
    )
  )

  (symbol (lib_id "kria-k26-devboard:C_10u_0603") (at 379.73 100.33 270) (mirror x) (unit 1)
    (in_bom yes) (on_board yes) (dnp no) (fields_autoplaced)
    (property "Reference" "C114" (at 377.19 96.5136 90)
      (effects (font (size 1.524 1.524)) (justify right))
    )
    (property "Value" "C_10u_0603" (at 375.92 100.33 0)
      (effects (font (size 1.27 1.27) (thickness 0.15)) (justify left bottom) hide)
    )
    (property "Footprint" "kria-k26-devboard-footprints:C_0603_1608Metric" (at 384.81 95.25 0)
      (effects (font (size 1.27 1.27) (thickness 0.15)) (justify left bottom) hide)
    )
    (property "Datasheet" " " (at 379.73 100.33 0)
      (effects (font (size 1.27 1.27) (thickness 0.15)) (justify left bottom) hide)
    )
    (property "Manufacturer" "Murata" (at 389.89 95.25 0)
      (effects (font (size 1.27 1.27) (thickness 0.15)) (justify left bottom) hide)
    )
    (property "MPN" "GRM188R61A106KE69D" (at 387.35 95.25 0)
      (effects (font (size 1.27 1.27) (thickness 0.15)) (justify left bottom) hide)
    )
    (property "Val" "10u" (at 377.19 99.6885 90)
      (effects (font (size 1.27 1.27) (thickness 0.15)) (justify right))
    )
    (property "License" "Apache-2.0" (at 356.87 80.01 0)
      (effects (font (size 1.27 1.27) (thickness 0.15)) (justify left bottom) hide)
    )
    (property "Author" "Antmicro" (at 354.33 80.01 0)
      (effects (font (size 1.27 1.27) (thickness 0.15)) (justify left bottom) hide)
    )
    (property "Voltage" "" (at 351.79 80.01 0)
      (effects (font (size 1.27 1.27)) (justify left bottom) hide)
    )
    (pin "1")
    (pin "2")
    (instances
      (project "kria-k26-devboard"
        (path ""
          (reference "C114") (unit 1)
        )
      )
    )
  )

  (symbol (lib_id "kria-k26-devboard:C_10n_0402") (at 367.665 95.25 90) (mirror x) (unit 1)
    (in_bom yes) (on_board yes) (dnp no) (fields_autoplaced)
    (property "Reference" "C113" (at 365.125 96.5263 90)
      (effects (font (size 1.524 1.524)) (justify left))
    )
    (property "Value" "C_10n_0402" (at 371.475 95.25 0)
      (effects (font (size 1.27 1.27) (thickness 0.15)) (justify left bottom) hide)
    )
    (property "Footprint" "kria-k26-devboard-footprints:C_0402_1005Metric" (at 362.585 100.33 0)
      (effects (font (size 1.27 1.27) (thickness 0.15)) (justify left bottom) hide)
    )
    (property "Datasheet" "https://search.murata.co.jp/Ceramy/image/img/A01X/G101/ENG/GRM155R71H103KA88-01.pdf" (at 367.665 95.25 0)
      (effects (font (size 1.27 1.27) (thickness 0.15)) (justify left bottom) hide)
    )
    (property "Manufacturer" "Murata" (at 357.505 100.33 0)
      (effects (font (size 1.27 1.27) (thickness 0.15)) (justify left bottom) hide)
    )
    (property "MPN" "GRM155R71H103KA88D" (at 360.045 100.33 0)
      (effects (font (size 1.27 1.27) (thickness 0.15)) (justify left bottom) hide)
    )
    (property "Val" "10n" (at 365.125 99.7012 90)
      (effects (font (size 1.27 1.27) (thickness 0.15)) (justify left))
    )
    (property "License" "Apache-2.0" (at 390.525 115.57 0)
      (effects (font (size 1.27 1.27) (thickness 0.15)) (justify left bottom) hide)
    )
    (property "Author" "Antmicro" (at 393.065 115.57 0)
      (effects (font (size 1.27 1.27) (thickness 0.15)) (justify left bottom) hide)
    )
    (property "Voltage" "50V" (at 395.605 115.57 0)
      (effects (font (size 1.27 1.27)) (justify left bottom) hide)
    )
    (property "Dielectric" "X7R" (at 398.145 115.57 0)
      (effects (font (size 1.27 1.27)) (justify left bottom) hide)
    )
    (pin "1")
    (pin "2")
    (instances
      (project "kria-k26-devboard"
        (path ""
          (reference "C113") (unit 1)
        )
      )
    )
  )

  (symbol (lib_id "kria-k26-devboard:C_100n_0402") (at 340.36 86.36 90) (mirror x) (unit 1)
    (in_bom yes) (on_board yes) (dnp no) (fields_autoplaced)
    (property "Reference" "C106" (at 337.185 87.6363 90)
      (effects (font (size 1.524 1.524)) (justify left))
    )
    (property "Value" "C_100n_0402" (at 344.17 86.36 0)
      (effects (font (size 1.27 1.27) (thickness 0.15)) (justify left bottom) hide)
    )
    (property "Footprint" "kria-k26-devboard-footprints:C_0402_1005Metric" (at 335.28 91.44 0)
      (effects (font (size 1.27 1.27) (thickness 0.15)) (justify left bottom) hide)
    )
    (property "Datasheet" "https://search.murata.co.jp/Ceramy/image/img/A01X/G101/ENG/GRM155R61H104KE14-01.pdf" (at 340.36 86.36 0)
      (effects (font (size 1.27 1.27) (thickness 0.15)) (justify left bottom) hide)
    )
    (property "Manufacturer" "Murata" (at 330.2 91.44 0)
      (effects (font (size 1.27 1.27) (thickness 0.15)) (justify left bottom) hide)
    )
    (property "MPN" "GRM155R61H104KE14D" (at 332.74 91.44 0)
      (effects (font (size 1.27 1.27) (thickness 0.15)) (justify left bottom) hide)
    )
    (property "Val" "100n" (at 337.185 90.8112 90)
      (effects (font (size 1.27 1.27) (thickness 0.15)) (justify left))
    )
    (property "License" "Apache-2.0" (at 363.22 106.68 0)
      (effects (font (size 1.27 1.27) (thickness 0.15)) (justify left bottom) hide)
    )
    (property "Author" "Antmicro" (at 365.76 106.68 0)
      (effects (font (size 1.27 1.27) (thickness 0.15)) (justify left bottom) hide)
    )
    (property "Voltage" "50V" (at 368.3 106.68 0)
      (effects (font (size 1.27 1.27)) (justify left bottom) hide)
    )
    (property "Dielectric" "X5R" (at 370.84 106.68 0)
      (effects (font (size 1.27 1.27)) (justify left bottom) hide)
    )
    (pin "1")
    (pin "2")
    (instances
      (project "kria-k26-devboard"
        (path ""
          (reference "C106") (unit 1)
        )
      )
    )
  )

  (symbol (lib_id "kria-k26-devboard:C_1u_0402") (at 351.79 86.36 90) (mirror x) (unit 1)
    (in_bom yes) (on_board yes) (dnp no) (fields_autoplaced)
    (property "Reference" "C110" (at 349.25 87.6363 90)
      (effects (font (size 1.524 1.524)) (justify left))
    )
    (property "Value" "C_1u_0402" (at 355.6 86.36 0)
      (effects (font (size 1.27 1.27) (thickness 0.15)) (justify left bottom) hide)
    )
    (property "Footprint" "kria-k26-devboard-footprints:C_0402_1005Metric" (at 346.71 91.44 0)
      (effects (font (size 1.27 1.27) (thickness 0.15)) (justify left bottom) hide)
    )
    (property "Datasheet" " " (at 351.79 86.36 0)
      (effects (font (size 1.27 1.27) (thickness 0.15)) (justify left bottom) hide)
    )
    (property "Manufacturer" "TDK" (at 341.63 91.44 0)
      (effects (font (size 1.27 1.27) (thickness 0.15)) (justify left bottom) hide)
    )
    (property "MPN" "C1005X6S1A105K050BC" (at 344.17 91.44 0)
      (effects (font (size 1.27 1.27) (thickness 0.15)) (justify left bottom) hide)
    )
    (property "Val" "1u" (at 349.25 90.8112 90)
      (effects (font (size 1.27 1.27) (thickness 0.15)) (justify left))
    )
    (property "License" "Apache-2.0" (at 374.65 106.68 0)
      (effects (font (size 1.27 1.27) (thickness 0.15)) (justify left bottom) hide)
    )
    (property "Author" "Antmicro" (at 377.19 106.68 0)
      (effects (font (size 1.27 1.27) (thickness 0.15)) (justify left bottom) hide)
    )
    (property "Voltage" "" (at 379.73 106.68 0)
      (effects (font (size 1.27 1.27)) (justify left bottom) hide)
    )
    (property "Dielectric" "" (at 382.27 106.68 0)
      (effects (font (size 1.27 1.27)) (justify left bottom) hide)
    )
    (pin "1")
    (pin "2")
    (instances
      (project "kria-k26-devboard"
        (path ""
          (reference "C110") (unit 1)
        )
      )
    )
  )

  (symbol (lib_id "kria-k26-devboard:GND") (at 340.36 91.44 0) (mirror y) (unit 1)
    (in_bom yes) (on_board yes) (dnp no) (fields_autoplaced)
    (property "Reference" "#PWR0121" (at 340.36 97.79 0)
      (effects (font (size 1.27 1.27)) hide)
    )
    (property "Value" "GND" (at 340.36 96.52 0)
      (effects (font (size 1.27 1.27)))
    )
    (property "Footprint" "" (at 331.47 99.06 0)
      (effects (font (size 1.27 1.27) (thickness 0.15)) (justify left bottom) hide)
    )
    (property "Datasheet" "" (at 331.47 104.14 0)
      (effects (font (size 1.27 1.27) (thickness 0.15)) (justify left bottom) hide)
    )
    (property "Author" "Antmicro" (at 331.47 99.06 0)
      (effects (font (size 1.27 1.27) (thickness 0.15)) (justify left bottom) hide)
    )
    (property "License" "Apache-2.0" (at 331.47 101.6 0)
      (effects (font (size 1.27 1.27) (thickness 0.15)) (justify left bottom) hide)
    )
    (pin "1")
    (instances
      (project "kria-k26-devboard"
        (path ""
          (reference "#PWR0121") (unit 1)
        )
      )
    )
  )

  (symbol (lib_id "kria-k26-devboard:GND") (at 367.665 100.33 0) (mirror y) (unit 1)
    (in_bom yes) (on_board yes) (dnp no) (fields_autoplaced)
    (property "Reference" "#PWR0124" (at 367.665 106.68 0)
      (effects (font (size 1.27 1.27)) hide)
    )
    (property "Value" "GND" (at 367.665 105.41 0)
      (effects (font (size 1.27 1.27)))
    )
    (property "Footprint" "" (at 358.775 107.95 0)
      (effects (font (size 1.27 1.27) (thickness 0.15)) (justify left bottom) hide)
    )
    (property "Datasheet" "" (at 358.775 113.03 0)
      (effects (font (size 1.27 1.27) (thickness 0.15)) (justify left bottom) hide)
    )
    (property "Author" "Antmicro" (at 358.775 107.95 0)
      (effects (font (size 1.27 1.27) (thickness 0.15)) (justify left bottom) hide)
    )
    (property "License" "Apache-2.0" (at 358.775 110.49 0)
      (effects (font (size 1.27 1.27) (thickness 0.15)) (justify left bottom) hide)
    )
    (pin "1")
    (instances
      (project "kria-k26-devboard"
        (path ""
          (reference "#PWR0124") (unit 1)
        )
      )
    )
  )

  (symbol (lib_id "kria-k26-devboard:C_100n_0402") (at 340.106 71.12 90) (mirror x) (unit 1)
    (in_bom yes) (on_board yes) (dnp no) (fields_autoplaced)
    (property "Reference" "C105" (at 336.931 72.3963 90)
      (effects (font (size 1.524 1.524)) (justify left))
    )
    (property "Value" "C_100n_0402" (at 343.916 71.12 0)
      (effects (font (size 1.27 1.27) (thickness 0.15)) (justify left bottom) hide)
    )
    (property "Footprint" "kria-k26-devboard-footprints:C_0402_1005Metric" (at 335.026 76.2 0)
      (effects (font (size 1.27 1.27) (thickness 0.15)) (justify left bottom) hide)
    )
    (property "Datasheet" "https://search.murata.co.jp/Ceramy/image/img/A01X/G101/ENG/GRM155R61H104KE14-01.pdf" (at 340.106 71.12 0)
      (effects (font (size 1.27 1.27) (thickness 0.15)) (justify left bottom) hide)
    )
    (property "Manufacturer" "Murata" (at 329.946 76.2 0)
      (effects (font (size 1.27 1.27) (thickness 0.15)) (justify left bottom) hide)
    )
    (property "MPN" "GRM155R61H104KE14D" (at 332.486 76.2 0)
      (effects (font (size 1.27 1.27) (thickness 0.15)) (justify left bottom) hide)
    )
    (property "Val" "100n" (at 336.931 75.5712 90)
      (effects (font (size 1.27 1.27) (thickness 0.15)) (justify left))
    )
    (property "License" "Apache-2.0" (at 362.966 91.44 0)
      (effects (font (size 1.27 1.27) (thickness 0.15)) (justify left bottom) hide)
    )
    (property "Author" "Antmicro" (at 365.506 91.44 0)
      (effects (font (size 1.27 1.27) (thickness 0.15)) (justify left bottom) hide)
    )
    (property "Voltage" "50V" (at 368.046 91.44 0)
      (effects (font (size 1.27 1.27)) (justify left bottom) hide)
    )
    (property "Dielectric" "X5R" (at 370.586 91.44 0)
      (effects (font (size 1.27 1.27)) (justify left bottom) hide)
    )
    (pin "1")
    (pin "2")
    (instances
      (project "kria-k26-devboard"
        (path ""
          (reference "C105") (unit 1)
        )
      )
    )
  )

  (symbol (lib_id "kria-k26-devboard:C_1u_0402") (at 351.536 71.12 90) (mirror x) (unit 1)
    (in_bom yes) (on_board yes) (dnp no) (fields_autoplaced)
    (property "Reference" "C109" (at 348.361 72.3963 90)
      (effects (font (size 1.524 1.524)) (justify left))
    )
    (property "Value" "C_1u_0402" (at 355.346 71.12 0)
      (effects (font (size 1.27 1.27) (thickness 0.15)) (justify left bottom) hide)
    )
    (property "Footprint" "kria-k26-devboard-footprints:C_0402_1005Metric" (at 346.456 76.2 0)
      (effects (font (size 1.27 1.27) (thickness 0.15)) (justify left bottom) hide)
    )
    (property "Datasheet" " " (at 351.536 71.12 0)
      (effects (font (size 1.27 1.27) (thickness 0.15)) (justify left bottom) hide)
    )
    (property "Manufacturer" "TDK" (at 341.376 76.2 0)
      (effects (font (size 1.27 1.27) (thickness 0.15)) (justify left bottom) hide)
    )
    (property "MPN" "C1005X6S1A105K050BC" (at 343.916 76.2 0)
      (effects (font (size 1.27 1.27) (thickness 0.15)) (justify left bottom) hide)
    )
    (property "Val" "1u" (at 348.361 75.5712 90)
      (effects (font (size 1.27 1.27) (thickness 0.15)) (justify left))
    )
    (property "License" "Apache-2.0" (at 374.396 91.44 0)
      (effects (font (size 1.27 1.27) (thickness 0.15)) (justify left bottom) hide)
    )
    (property "Author" "Antmicro" (at 376.936 91.44 0)
      (effects (font (size 1.27 1.27) (thickness 0.15)) (justify left bottom) hide)
    )
    (property "Voltage" "" (at 379.476 91.44 0)
      (effects (font (size 1.27 1.27)) (justify left bottom) hide)
    )
    (property "Dielectric" "" (at 382.016 91.44 0)
      (effects (font (size 1.27 1.27)) (justify left bottom) hide)
    )
    (pin "1")
    (pin "2")
    (instances
      (project "kria-k26-devboard"
        (path ""
          (reference "C109") (unit 1)
        )
      )
    )
  )

  (symbol (lib_id "kria-k26-devboard:GND") (at 340.106 76.2 0) (mirror y) (unit 1)
    (in_bom yes) (on_board yes) (dnp no) (fields_autoplaced)
    (property "Reference" "#PWR0120" (at 340.106 82.55 0)
      (effects (font (size 1.27 1.27)) hide)
    )
    (property "Value" "GND" (at 340.106 81.28 0)
      (effects (font (size 1.27 1.27)))
    )
    (property "Footprint" "" (at 331.216 83.82 0)
      (effects (font (size 1.27 1.27) (thickness 0.15)) (justify left bottom) hide)
    )
    (property "Datasheet" "" (at 331.216 88.9 0)
      (effects (font (size 1.27 1.27) (thickness 0.15)) (justify left bottom) hide)
    )
    (property "Author" "Antmicro" (at 331.216 83.82 0)
      (effects (font (size 1.27 1.27) (thickness 0.15)) (justify left bottom) hide)
    )
    (property "License" "Apache-2.0" (at 331.216 86.36 0)
      (effects (font (size 1.27 1.27) (thickness 0.15)) (justify left bottom) hide)
    )
    (pin "1")
    (instances
      (project "kria-k26-devboard"
        (path ""
          (reference "#PWR0120") (unit 1)
        )
      )
    )
  )

  (symbol (lib_id "kria-k26-devboard:C_100n_0402") (at 340.36 102.87 90) (mirror x) (unit 1)
    (in_bom yes) (on_board yes) (dnp no) (fields_autoplaced)
    (property "Reference" "C107" (at 337.82 104.1463 90)
      (effects (font (size 1.524 1.524)) (justify left))
    )
    (property "Value" "C_100n_0402" (at 344.17 102.87 0)
      (effects (font (size 1.27 1.27) (thickness 0.15)) (justify left bottom) hide)
    )
    (property "Footprint" "kria-k26-devboard-footprints:C_0402_1005Metric" (at 335.28 107.95 0)
      (effects (font (size 1.27 1.27) (thickness 0.15)) (justify left bottom) hide)
    )
    (property "Datasheet" "https://search.murata.co.jp/Ceramy/image/img/A01X/G101/ENG/GRM155R61H104KE14-01.pdf" (at 340.36 102.87 0)
      (effects (font (size 1.27 1.27) (thickness 0.15)) (justify left bottom) hide)
    )
    (property "Manufacturer" "Murata" (at 330.2 107.95 0)
      (effects (font (size 1.27 1.27) (thickness 0.15)) (justify left bottom) hide)
    )
    (property "MPN" "GRM155R61H104KE14D" (at 332.74 107.95 0)
      (effects (font (size 1.27 1.27) (thickness 0.15)) (justify left bottom) hide)
    )
    (property "Val" "100n" (at 337.82 107.3212 90)
      (effects (font (size 1.27 1.27) (thickness 0.15)) (justify left))
    )
    (property "License" "Apache-2.0" (at 363.22 123.19 0)
      (effects (font (size 1.27 1.27) (thickness 0.15)) (justify left bottom) hide)
    )
    (property "Author" "Antmicro" (at 365.76 123.19 0)
      (effects (font (size 1.27 1.27) (thickness 0.15)) (justify left bottom) hide)
    )
    (property "Voltage" "50V" (at 368.3 123.19 0)
      (effects (font (size 1.27 1.27)) (justify left bottom) hide)
    )
    (property "Dielectric" "X5R" (at 370.84 123.19 0)
      (effects (font (size 1.27 1.27)) (justify left bottom) hide)
    )
    (pin "1")
    (pin "2")
    (instances
      (project "kria-k26-devboard"
        (path ""
          (reference "C107") (unit 1)
        )
      )
    )
  )

  (symbol (lib_id "kria-k26-devboard:C_1u_0402") (at 351.79 102.87 90) (mirror x) (unit 1)
    (in_bom yes) (on_board yes) (dnp no) (fields_autoplaced)
    (property "Reference" "C111" (at 349.25 104.1463 90)
      (effects (font (size 1.524 1.524)) (justify left))
    )
    (property "Value" "C_1u_0402" (at 355.6 102.87 0)
      (effects (font (size 1.27 1.27) (thickness 0.15)) (justify left bottom) hide)
    )
    (property "Footprint" "kria-k26-devboard-footprints:C_0402_1005Metric" (at 346.71 107.95 0)
      (effects (font (size 1.27 1.27) (thickness 0.15)) (justify left bottom) hide)
    )
    (property "Datasheet" " " (at 351.79 102.87 0)
      (effects (font (size 1.27 1.27) (thickness 0.15)) (justify left bottom) hide)
    )
    (property "Manufacturer" "TDK" (at 341.63 107.95 0)
      (effects (font (size 1.27 1.27) (thickness 0.15)) (justify left bottom) hide)
    )
    (property "MPN" "C1005X6S1A105K050BC" (at 344.17 107.95 0)
      (effects (font (size 1.27 1.27) (thickness 0.15)) (justify left bottom) hide)
    )
    (property "Val" "1u" (at 349.25 107.3212 90)
      (effects (font (size 1.27 1.27) (thickness 0.15)) (justify left))
    )
    (property "License" "Apache-2.0" (at 374.65 123.19 0)
      (effects (font (size 1.27 1.27) (thickness 0.15)) (justify left bottom) hide)
    )
    (property "Author" "Antmicro" (at 377.19 123.19 0)
      (effects (font (size 1.27 1.27) (thickness 0.15)) (justify left bottom) hide)
    )
    (property "Voltage" "" (at 379.73 123.19 0)
      (effects (font (size 1.27 1.27)) (justify left bottom) hide)
    )
    (property "Dielectric" "" (at 382.27 123.19 0)
      (effects (font (size 1.27 1.27)) (justify left bottom) hide)
    )
    (pin "1")
    (pin "2")
    (instances
      (project "kria-k26-devboard"
        (path ""
          (reference "C111") (unit 1)
        )
      )
    )
  )

  (symbol (lib_id "kria-k26-devboard:GND") (at 340.36 107.95 0) (mirror y) (unit 1)
    (in_bom yes) (on_board yes) (dnp no) (fields_autoplaced)
    (property "Reference" "#PWR0122" (at 340.36 114.3 0)
      (effects (font (size 1.27 1.27)) hide)
    )
    (property "Value" "GND" (at 340.36 113.03 0)
      (effects (font (size 1.27 1.27)))
    )
    (property "Footprint" "" (at 331.47 115.57 0)
      (effects (font (size 1.27 1.27) (thickness 0.15)) (justify left bottom) hide)
    )
    (property "Datasheet" "" (at 331.47 120.65 0)
      (effects (font (size 1.27 1.27) (thickness 0.15)) (justify left bottom) hide)
    )
    (property "Author" "Antmicro" (at 331.47 115.57 0)
      (effects (font (size 1.27 1.27) (thickness 0.15)) (justify left bottom) hide)
    )
    (property "License" "Apache-2.0" (at 331.47 118.11 0)
      (effects (font (size 1.27 1.27) (thickness 0.15)) (justify left bottom) hide)
    )
    (pin "1")
    (instances
      (project "kria-k26-devboard"
        (path ""
          (reference "#PWR0122") (unit 1)
        )
      )
    )
  )

  (symbol (lib_id "kria-k26-devboard:GND") (at 340.36 122.555 0) (mirror y) (unit 1)
    (in_bom yes) (on_board yes) (dnp no) (fields_autoplaced)
    (property "Reference" "#PWR0123" (at 340.36 128.905 0)
      (effects (font (size 1.27 1.27)) hide)
    )
    (property "Value" "GND" (at 340.36 127.635 0)
      (effects (font (size 1.27 1.27)))
    )
    (property "Footprint" "" (at 331.47 130.175 0)
      (effects (font (size 1.27 1.27) (thickness 0.15)) (justify left bottom) hide)
    )
    (property "Datasheet" "" (at 331.47 135.255 0)
      (effects (font (size 1.27 1.27) (thickness 0.15)) (justify left bottom) hide)
    )
    (property "Author" "Antmicro" (at 331.47 130.175 0)
      (effects (font (size 1.27 1.27) (thickness 0.15)) (justify left bottom) hide)
    )
    (property "License" "Apache-2.0" (at 331.47 132.715 0)
      (effects (font (size 1.27 1.27) (thickness 0.15)) (justify left bottom) hide)
    )
    (pin "1")
    (instances
      (project "kria-k26-devboard"
        (path ""
          (reference "#PWR0123") (unit 1)
        )
      )
    )
  )

  (symbol (lib_id "kria-k26-devboard:C_1u_0402") (at 351.79 117.475 90) (mirror x) (unit 1)
    (in_bom yes) (on_board yes) (dnp no) (fields_autoplaced)
    (property "Reference" "C112" (at 354.33 118.7513 90)
      (effects (font (size 1.524 1.524)) (justify right))
    )
    (property "Value" "C_1u_0402" (at 355.6 117.475 0)
      (effects (font (size 1.27 1.27) (thickness 0.15)) (justify left bottom) hide)
    )
    (property "Footprint" "kria-k26-devboard-footprints:C_0402_1005Metric" (at 346.71 122.555 0)
      (effects (font (size 1.27 1.27) (thickness 0.15)) (justify left bottom) hide)
    )
    (property "Datasheet" " " (at 351.79 117.475 0)
      (effects (font (size 1.27 1.27) (thickness 0.15)) (justify left bottom) hide)
    )
    (property "Manufacturer" "TDK" (at 341.63 122.555 0)
      (effects (font (size 1.27 1.27) (thickness 0.15)) (justify left bottom) hide)
    )
    (property "MPN" "C1005X6S1A105K050BC" (at 344.17 122.555 0)
      (effects (font (size 1.27 1.27) (thickness 0.15)) (justify left bottom) hide)
    )
    (property "Val" "1u" (at 354.33 121.9262 90)
      (effects (font (size 1.27 1.27) (thickness 0.15)) (justify right))
    )
    (property "License" "Apache-2.0" (at 374.65 137.795 0)
      (effects (font (size 1.27 1.27) (thickness 0.15)) (justify left bottom) hide)
    )
    (property "Author" "Antmicro" (at 377.19 137.795 0)
      (effects (font (size 1.27 1.27) (thickness 0.15)) (justify left bottom) hide)
    )
    (property "Voltage" "" (at 379.73 137.795 0)
      (effects (font (size 1.27 1.27)) (justify left bottom) hide)
    )
    (property "Dielectric" "" (at 382.27 137.795 0)
      (effects (font (size 1.27 1.27)) (justify left bottom) hide)
    )
    (pin "1")
    (pin "2")
    (instances
      (project "kria-k26-devboard"
        (path ""
          (reference "C112") (unit 1)
        )
      )
    )
  )

  (symbol (lib_id "kria-k26-devboard:C_100n_0402") (at 340.36 117.475 90) (mirror x) (unit 1)
    (in_bom yes) (on_board yes) (dnp no) (fields_autoplaced)
    (property "Reference" "C108" (at 337.82 118.7513 90)
      (effects (font (size 1.524 1.524)) (justify left))
    )
    (property "Value" "C_100n_0402" (at 344.17 117.475 0)
      (effects (font (size 1.27 1.27) (thickness 0.15)) (justify left bottom) hide)
    )
    (property "Footprint" "kria-k26-devboard-footprints:C_0402_1005Metric" (at 335.28 122.555 0)
      (effects (font (size 1.27 1.27) (thickness 0.15)) (justify left bottom) hide)
    )
    (property "Datasheet" "https://search.murata.co.jp/Ceramy/image/img/A01X/G101/ENG/GRM155R61H104KE14-01.pdf" (at 340.36 117.475 0)
      (effects (font (size 1.27 1.27) (thickness 0.15)) (justify left bottom) hide)
    )
    (property "Manufacturer" "Murata" (at 330.2 122.555 0)
      (effects (font (size 1.27 1.27) (thickness 0.15)) (justify left bottom) hide)
    )
    (property "MPN" "GRM155R61H104KE14D" (at 332.74 122.555 0)
      (effects (font (size 1.27 1.27) (thickness 0.15)) (justify left bottom) hide)
    )
    (property "Val" "100n" (at 337.82 121.9262 90)
      (effects (font (size 1.27 1.27) (thickness 0.15)) (justify left))
    )
    (property "License" "Apache-2.0" (at 363.22 137.795 0)
      (effects (font (size 1.27 1.27) (thickness 0.15)) (justify left bottom) hide)
    )
    (property "Author" "Antmicro" (at 365.76 137.795 0)
      (effects (font (size 1.27 1.27) (thickness 0.15)) (justify left bottom) hide)
    )
    (property "Voltage" "50V" (at 368.3 137.795 0)
      (effects (font (size 1.27 1.27)) (justify left bottom) hide)
    )
    (property "Dielectric" "X5R" (at 370.84 137.795 0)
      (effects (font (size 1.27 1.27)) (justify left bottom) hide)
    )
    (pin "1")
    (pin "2")
    (instances
      (project "kria-k26-devboard"
        (path ""
          (reference "C108") (unit 1)
        )
      )
    )
  )

  (symbol (lib_id "kria-k26-devboard:R_2k2_0402") (at 128.27 134.62 0) (unit 1)
    (in_bom yes) (on_board yes) (dnp no)
    (property "Reference" "R71" (at 126.365 133.35 0)
      (effects (font (size 1.524 1.524)))
    )
    (property "Value" "R_2k2_0402" (at 128.27 138.43 0)
      (effects (font (size 1.27 1.27) (thickness 0.15)) (justify left bottom) hide)
    )
    (property "Footprint" "kria-k26-devboard-footprints:R_0402_1005Metric" (at 133.35 129.54 0)
      (effects (font (size 1.27 1.27) (thickness 0.15)) (justify left bottom) hide)
    )
    (property "Datasheet" "https://www.bourns.com/docs/product-datasheets/cr.pdf" (at 128.27 134.62 0)
      (effects (font (size 1.27 1.27) (thickness 0.15)) (justify left bottom) hide)
    )
    (property "Manufacturer" "Bourns" (at 133.35 124.46 0)
      (effects (font (size 1.27 1.27) (thickness 0.15)) (justify left bottom) hide)
    )
    (property "MPN" "CR0402-FX-2201GLF" (at 133.35 127 0)
      (effects (font (size 1.27 1.27) (thickness 0.15)) (justify left bottom) hide)
    )
    (property "Val" "2k2" (at 134.62 133.35 0)
      (effects (font (size 1.27 1.27) (thickness 0.15)))
    )
    (property "License" "Apache-2.0" (at 148.59 160.02 0)
      (effects (font (size 1.27 1.27) (thickness 0.15)) (justify left bottom) hide)
    )
    (property "Author" "Antmicro" (at 148.59 162.56 0)
      (effects (font (size 1.27 1.27) (thickness 0.15)) (justify left bottom) hide)
    )
    (property "Tolerance" "1%" (at 148.59 144.78 0)
      (effects (font (size 1.27 1.27)) (justify left bottom) hide)
    )
    (pin "1")
    (pin "2")
    (instances
      (project "kria-k26-devboard"
        (path ""
          (reference "R71") (unit 1)
        )
      )
    )
  )

  (symbol (lib_id "kria-k26-devboard:R_2k2_0402") (at 122.555 116.84 90) (mirror x) (unit 1)
    (in_bom yes) (on_board yes) (dnp no) (fields_autoplaced)
    (property "Reference" "R76" (at 120.015 118.11 90)
      (effects (font (size 1.524 1.524)) (justify left))
    )
    (property "Value" "R_2k2_0402" (at 126.365 116.84 0)
      (effects (font (size 1.27 1.27) (thickness 0.15)) (justify left bottom) hide)
    )
    (property "Footprint" "kria-k26-devboard-footprints:R_0402_1005Metric" (at 117.475 121.92 0)
      (effects (font (size 1.27 1.27) (thickness 0.15)) (justify left bottom) hide)
    )
    (property "Datasheet" "https://www.bourns.com/docs/product-datasheets/cr.pdf" (at 122.555 116.84 0)
      (effects (font (size 1.27 1.27) (thickness 0.15)) (justify left bottom) hide)
    )
    (property "Manufacturer" "Bourns" (at 112.395 121.92 0)
      (effects (font (size 1.27 1.27) (thickness 0.15)) (justify left bottom) hide)
    )
    (property "MPN" "CR0402-FX-2201GLF" (at 114.935 121.92 0)
      (effects (font (size 1.27 1.27) (thickness 0.15)) (justify left bottom) hide)
    )
    (property "Val" "2k2" (at 120.015 121.2849 90)
      (effects (font (size 1.27 1.27) (thickness 0.15)) (justify left))
    )
    (property "License" "Apache-2.0" (at 147.955 137.16 0)
      (effects (font (size 1.27 1.27) (thickness 0.15)) (justify left bottom) hide)
    )
    (property "Author" "Antmicro" (at 150.495 137.16 0)
      (effects (font (size 1.27 1.27) (thickness 0.15)) (justify left bottom) hide)
    )
    (property "Tolerance" "1%" (at 132.715 137.16 0)
      (effects (font (size 1.27 1.27)) (justify left bottom) hide)
    )
    (pin "1")
    (pin "2")
    (instances
      (project "kria-k26-devboard"
        (path ""
          (reference "R76") (unit 1)
        )
      )
    )
  )

  (symbol (lib_id "kria-k26-devboard:R_2k49_0402") (at 55.88 222.885 270) (unit 1)
    (in_bom yes) (on_board yes) (dnp no) (fields_autoplaced)
    (property "Reference" "R70" (at 58.42 224.155 90)
      (effects (font (size 1.524 1.524)) (justify left))
    )
    (property "Value" "R_2k49_0402" (at 52.07 222.885 0)
      (effects (font (size 1.27 1.27) (thickness 0.15)) (justify left bottom) hide)
    )
    (property "Footprint" "kria-k26-devboard-footprints:R_0402_1005Metric" (at 60.96 227.965 0)
      (effects (font (size 1.27 1.27) (thickness 0.15)) (justify left bottom) hide)
    )
    (property "Datasheet" "https://www.bourns.com/docs/product-datasheets/cr.pdf" (at 55.88 222.885 0)
      (effects (font (size 1.27 1.27) (thickness 0.15)) (justify left bottom) hide)
    )
    (property "Manufacturer" "Bourns" (at 66.04 227.965 0)
      (effects (font (size 1.27 1.27) (thickness 0.15)) (justify left bottom) hide)
    )
    (property "MPN" "CR0402-FX-2491GLF" (at 63.5 227.965 0)
      (effects (font (size 1.27 1.27) (thickness 0.15)) (justify left bottom) hide)
    )
    (property "Val" "2k49" (at 58.42 227.3299 90)
      (effects (font (size 1.27 1.27) (thickness 0.15)) (justify left))
    )
    (property "License" "Apache-2.0" (at 30.48 243.205 0)
      (effects (font (size 1.27 1.27) (thickness 0.15)) (justify left bottom) hide)
    )
    (property "Author" "Antmicro" (at 27.94 243.205 0)
      (effects (font (size 1.27 1.27) (thickness 0.15)) (justify left bottom) hide)
    )
    (property "Tolerance" "1%" (at 45.72 243.205 0)
      (effects (font (size 1.27 1.27)) (justify left bottom) hide)
    )
    (pin "1")
    (pin "2")
    (instances
      (project "kria-k26-devboard"
        (path ""
          (reference "R70") (unit 1)
        )
      )
    )
  )

  (symbol (lib_id "kria-k26-devboard:R_5k76_0402") (at 55.88 212.725 270) (unit 1)
    (in_bom yes) (on_board yes) (dnp no) (fields_autoplaced)
    (property "Reference" "R69" (at 58.42 213.995 90)
      (effects (font (size 1.524 1.524)) (justify left))
    )
    (property "Value" "R_5k76_0402" (at 52.07 212.725 0)
      (effects (font (size 1.27 1.27) (thickness 0.15)) (justify left bottom) hide)
    )
    (property "Footprint" "kria-k26-devboard-footprints:R_0402_1005Metric" (at 60.96 217.805 0)
      (effects (font (size 1.27 1.27) (thickness 0.15)) (justify left bottom) hide)
    )
    (property "Datasheet" "https://www.bourns.com/docs/product-datasheets/cr.pdf" (at 55.88 212.725 0)
      (effects (font (size 1.27 1.27) (thickness 0.15)) (justify left bottom) hide)
    )
    (property "Manufacturer" "Bourns" (at 66.04 217.805 0)
      (effects (font (size 1.27 1.27) (thickness 0.15)) (justify left bottom) hide)
    )
    (property "MPN" "CR0402-FX-5761GLF" (at 63.5 217.805 0)
      (effects (font (size 1.27 1.27) (thickness 0.15)) (justify left bottom) hide)
    )
    (property "Val" "5k76" (at 58.42 217.1699 90)
      (effects (font (size 1.27 1.27) (thickness 0.15)) (justify left))
    )
    (property "License" "Apache-2.0" (at 30.48 233.045 0)
      (effects (font (size 1.27 1.27) (thickness 0.15)) (justify left bottom) hide)
    )
    (property "Author" "Antmicro" (at 27.94 233.045 0)
      (effects (font (size 1.27 1.27) (thickness 0.15)) (justify left bottom) hide)
    )
    (property "Tolerance" "1%" (at 45.72 233.045 0)
      (effects (font (size 1.27 1.27)) (justify left bottom) hide)
    )
    (pin "1")
    (pin "2")
    (instances
      (project "kria-k26-devboard"
        (path ""
          (reference "R69") (unit 1)
        )
      )
    )
  )

  (symbol (lib_id "kria-k26-devboard:GND") (at 55.88 232.41 0) (unit 1)
    (in_bom yes) (on_board yes) (dnp no) (fields_autoplaced)
    (property "Reference" "#PWR0108" (at 55.88 238.76 0)
      (effects (font (size 1.27 1.27)) hide)
    )
    (property "Value" "GND" (at 55.88 237.49 0)
      (effects (font (size 1.27 1.27)))
    )
    (property "Footprint" "" (at 64.77 240.03 0)
      (effects (font (size 1.27 1.27) (thickness 0.15)) (justify left bottom) hide)
    )
    (property "Datasheet" "" (at 64.77 245.11 0)
      (effects (font (size 1.27 1.27) (thickness 0.15)) (justify left bottom) hide)
    )
    (property "Author" "Antmicro" (at 64.77 240.03 0)
      (effects (font (size 1.27 1.27) (thickness 0.15)) (justify left bottom) hide)
    )
    (property "License" "Apache-2.0" (at 64.77 242.57 0)
      (effects (font (size 1.27 1.27) (thickness 0.15)) (justify left bottom) hide)
    )
    (pin "1")
    (instances
      (project "kria-k26-devboard"
        (path ""
          (reference "#PWR0108") (unit 1)
        )
      )
    )
  )

  (symbol (lib_id "kria-k26-devboard:DTC014T_SOT-416") (at 294.64 121.92 0) (mirror y) (unit 1)
    (in_bom yes) (on_board yes) (dnp no) (fields_autoplaced)
    (property "Reference" "Q4" (at 284.48 120.6499 0)
      (effects (font (size 1.27 1.27)) (justify left))
    )
    (property "Value" "DTC014T_SOT-416" (at 284.48 123.1899 0)
      (effects (font (size 1.27 1.27) (thickness 0.15)) (justify left) hide)
    )
    (property "Footprint" "kria-k26-devboard-footprints:SOT-416" (at 289.56 129.54 0)
      (effects (font (size 1.27 1.27) (thickness 0.15)) (justify left bottom) hide)
    )
    (property "Datasheet" "https://www.rohm.com/datasheet?p=DTC014TEB&dist=Mouser&media=referral&source=mouser.com&campaign=Mouser" (at 294.64 121.92 0)
      (effects (font (size 1.27 1.27) (thickness 0.15)) (justify left bottom) hide)
    )
    (property "Manufacturer" "ROHM Semiconductor" (at 279.4 124.46 0)
      (effects (font (size 1.27 1.27) (thickness 0.15)) (justify left bottom) hide)
    )
    (property "MPN" "DTC014TEBTL" (at 284.48 123.1899 0)
      (effects (font (size 1.27 1.27) (thickness 0.15)) (justify left))
    )
    (property "Author" "Antmicro" (at 269.24 142.24 0)
      (effects (font (size 1.27 1.27) (thickness 0.15)) (justify left bottom) hide)
    )
    (property "License" "Apache-2.0" (at 269.24 144.78 0)
      (effects (font (size 1.27 1.27) (thickness 0.15)) (justify left bottom) hide)
    )
    (pin "1")
    (pin "2")
    (pin "3")
    (instances
      (project "kria-k26-devboard"
        (path ""
          (reference "Q4") (unit 1)
        )
      )
    )
  )

  (symbol (lib_id "kria-k26-devboard:DTC014T_SOT-416") (at 304.165 110.49 0) (mirror y) (unit 1)
    (in_bom yes) (on_board yes) (dnp no)
    (property "Reference" "Q5" (at 299.72 102.87 0)
      (effects (font (size 1.27 1.27)) (justify right))
    )
    (property "Value" "DTC014T_SOT-416" (at 294.005 111.7599 0)
      (effects (font (size 1.27 1.27) (thickness 0.15)) (justify left) hide)
    )
    (property "Footprint" "kria-k26-devboard-footprints:SOT-416" (at 299.085 118.11 0)
      (effects (font (size 1.27 1.27) (thickness 0.15)) (justify left bottom) hide)
    )
    (property "Datasheet" "https://www.rohm.com/datasheet?p=DTC014TEB&dist=Mouser&media=referral&source=mouser.com&campaign=Mouser" (at 304.165 110.49 0)
      (effects (font (size 1.27 1.27) (thickness 0.15)) (justify left bottom) hide)
    )
    (property "Manufacturer" "ROHM Semiconductor" (at 288.925 113.03 0)
      (effects (font (size 1.27 1.27) (thickness 0.15)) (justify left bottom) hide)
    )
    (property "MPN" "DTC014TEBTL" (at 299.72 105.41 0)
      (effects (font (size 1.27 1.27) (thickness 0.15)) (justify right))
    )
    (property "Author" "Antmicro" (at 278.765 130.81 0)
      (effects (font (size 1.27 1.27) (thickness 0.15)) (justify left bottom) hide)
    )
    (property "License" "Apache-2.0" (at 278.765 133.35 0)
      (effects (font (size 1.27 1.27) (thickness 0.15)) (justify left bottom) hide)
    )
    (pin "1")
    (pin "2")
    (pin "3")
    (instances
      (project "kria-k26-devboard"
        (path ""
          (reference "Q5") (unit 1)
        )
      )
    )
  )

  (symbol (lib_id "kria-k26-devboard:GND") (at 296.545 115.57 0) (unit 1)
    (in_bom yes) (on_board yes) (dnp no)
    (property "Reference" "#PWR0119" (at 296.545 121.92 0)
      (effects (font (size 1.27 1.27)) hide)
    )
    (property "Value" "GND" (at 296.545 119.38 0)
      (effects (font (size 1.27 1.27)))
    )
    (property "Footprint" "" (at 305.435 123.19 0)
      (effects (font (size 1.27 1.27) (thickness 0.15)) (justify left bottom) hide)
    )
    (property "Datasheet" "" (at 305.435 128.27 0)
      (effects (font (size 1.27 1.27) (thickness 0.15)) (justify left bottom) hide)
    )
    (property "Author" "Antmicro" (at 305.435 123.19 0)
      (effects (font (size 1.27 1.27) (thickness 0.15)) (justify left bottom) hide)
    )
    (property "License" "Apache-2.0" (at 305.435 125.73 0)
      (effects (font (size 1.27 1.27) (thickness 0.15)) (justify left bottom) hide)
    )
    (pin "1")
    (instances
      (project "kria-k26-devboard"
        (path ""
          (reference "#PWR0119") (unit 1)
        )
      )
    )
  )

  (symbol (lib_id "kria-k26-devboard:GND") (at 111.125 226.695 0) (unit 1)
    (in_bom yes) (on_board yes) (dnp no) (fields_autoplaced)
    (property "Reference" "#PWR0115" (at 111.125 233.045 0)
      (effects (font (size 1.27 1.27)) hide)
    )
    (property "Value" "GND" (at 111.125 231.775 0)
      (effects (font (size 1.27 1.27)))
    )
    (property "Footprint" "" (at 120.015 234.315 0)
      (effects (font (size 1.27 1.27) (thickness 0.15)) (justify left bottom) hide)
    )
    (property "Datasheet" "" (at 120.015 239.395 0)
      (effects (font (size 1.27 1.27) (thickness 0.15)) (justify left bottom) hide)
    )
    (property "Author" "Antmicro" (at 120.015 234.315 0)
      (effects (font (size 1.27 1.27) (thickness 0.15)) (justify left bottom) hide)
    )
    (property "License" "Apache-2.0" (at 120.015 236.855 0)
      (effects (font (size 1.27 1.27) (thickness 0.15)) (justify left bottom) hide)
    )
    (pin "1")
    (instances
      (project "kria-k26-devboard"
        (path ""
          (reference "#PWR0115") (unit 1)
        )
      )
    )
  )

  (symbol (lib_id "kria-k26-devboard:GND") (at 86.995 227.965 0) (unit 1)
    (in_bom yes) (on_board yes) (dnp no) (fields_autoplaced)
    (property "Reference" "#PWR0114" (at 86.995 234.315 0)
      (effects (font (size 1.27 1.27)) hide)
    )
    (property "Value" "GND" (at 86.995 233.045 0)
      (effects (font (size 1.27 1.27)))
    )
    (property "Footprint" "" (at 95.885 235.585 0)
      (effects (font (size 1.27 1.27) (thickness 0.15)) (justify left bottom) hide)
    )
    (property "Datasheet" "" (at 95.885 240.665 0)
      (effects (font (size 1.27 1.27) (thickness 0.15)) (justify left bottom) hide)
    )
    (property "Author" "Antmicro" (at 95.885 235.585 0)
      (effects (font (size 1.27 1.27) (thickness 0.15)) (justify left bottom) hide)
    )
    (property "License" "Apache-2.0" (at 95.885 238.125 0)
      (effects (font (size 1.27 1.27) (thickness 0.15)) (justify left bottom) hide)
    )
    (pin "1")
    (instances
      (project "kria-k26-devboard"
        (path ""
          (reference "#PWR0114") (unit 1)
        )
      )
    )
  )

  (symbol (lib_id "kria-k26-devboard:C_100n_0402") (at 86.995 222.885 270) (unit 1)
    (in_bom yes) (on_board yes) (dnp no) (fields_autoplaced)
    (property "Reference" "C104" (at 89.535 224.1613 90)
      (effects (font (size 1.524 1.524)) (justify left))
    )
    (property "Value" "C_100n_0402" (at 83.185 222.885 0)
      (effects (font (size 1.27 1.27) (thickness 0.15)) (justify left bottom) hide)
    )
    (property "Footprint" "kria-k26-devboard-footprints:C_0402_1005Metric" (at 92.075 227.965 0)
      (effects (font (size 1.27 1.27) (thickness 0.15)) (justify left bottom) hide)
    )
    (property "Datasheet" "https://search.murata.co.jp/Ceramy/image/img/A01X/G101/ENG/GRM155R61H104KE14-01.pdf" (at 86.995 222.885 0)
      (effects (font (size 1.27 1.27) (thickness 0.15)) (justify left bottom) hide)
    )
    (property "Manufacturer" "Murata" (at 97.155 227.965 0)
      (effects (font (size 1.27 1.27) (thickness 0.15)) (justify left bottom) hide)
    )
    (property "MPN" "GRM155R61H104KE14D" (at 94.615 227.965 0)
      (effects (font (size 1.27 1.27) (thickness 0.15)) (justify left bottom) hide)
    )
    (property "Val" "100n" (at 89.535 227.3362 90)
      (effects (font (size 1.27 1.27) (thickness 0.15)) (justify left))
    )
    (property "License" "Apache-2.0" (at 64.135 243.205 0)
      (effects (font (size 1.27 1.27) (thickness 0.15)) (justify left bottom) hide)
    )
    (property "Author" "Antmicro" (at 61.595 243.205 0)
      (effects (font (size 1.27 1.27) (thickness 0.15)) (justify left bottom) hide)
    )
    (property "Voltage" "50V" (at 59.055 243.205 0)
      (effects (font (size 1.27 1.27)) (justify left bottom) hide)
    )
    (property "Dielectric" "X5R" (at 56.515 243.205 0)
      (effects (font (size 1.27 1.27)) (justify left bottom) hide)
    )
    (pin "1")
    (pin "2")
    (instances
      (project "kria-k26-devboard"
        (path ""
          (reference "C104") (unit 1)
        )
      )
    )
  )

  (symbol (lib_id "kria-k26-devboard:Oscillator_25MHz_ESC_2016MV") (at 113.03 220.345 0) (unit 1)
    (in_bom yes) (on_board yes) (dnp no) (fields_autoplaced)
    (property "Reference" "Y6" (at 122.555 210.185 0)
      (effects (font (size 1.27 1.27)))
    )
    (property "Value" "Oscillator_25MHz_ESC_2016MV" (at 122.555 212.725 0)
      (effects (font (size 1.27 1.27) (thickness 0.15)) hide)
    )
    (property "Footprint" "kria-k26-devboard-footprints:Oscillator_SMD_ECS_2016MV_2x1.6x0.85mm" (at 124.46 229.235 0)
      (effects (font (size 1.27 1.27) (thickness 0.15)) (justify left bottom) hide)
    )
    (property "Datasheet" "https://ecsxtal.com/store/pdf/ECS-2016MV.pdf" (at 108.585 217.17 0)
      (effects (font (size 1.27 1.27) (thickness 0.15)) (justify left bottom) hide)
    )
    (property "Manufacturer" "ECS Inc. International" (at 116.84 231.775 0)
      (effects (font (size 1.27 1.27) (thickness 0.15)) (justify left bottom) hide)
    )
    (property "MPN" "ECS-2016MV-250-CN-TR" (at 122.555 212.725 0)
      (effects (font (size 1.27 1.27) (thickness 0.15)))
    )
    (property "Author" "Antmicro" (at 146.05 238.125 0)
      (effects (font (size 1.27 1.27) (thickness 0.15)) (justify left bottom) hide)
    )
    (property "License" "Apache-2.0" (at 146.05 240.665 0)
      (effects (font (size 1.27 1.27) (thickness 0.15)) (justify left bottom) hide)
    )
    (property "VAL" "25 MHz" (at 122.555 215.265 0)
      (effects (font (size 1.27 1.27) (thickness 0.15)))
    )
    (property "Val" "25 MHz" (at 138.43 230.505 0)
      (effects (font (size 1.27 1.27) (thickness 0.15)) (justify left bottom))
    )
    (pin "1")
    (pin "2")
    (pin "3")
    (pin "4")
    (instances
      (project "kria-k26-devboard"
        (path ""
          (reference "Y6") (unit 1)
        )
      )
    )
  )

  (symbol (lib_id "kria-k26-devboard:R_2k49_0402") (at 44.45 222.885 270) (unit 1)
    (in_bom yes) (on_board yes) (dnp no) (fields_autoplaced)
    (property "Reference" "R68" (at 46.99 224.155 90)
      (effects (font (size 1.524 1.524)) (justify left))
    )
    (property "Value" "R_2k49_0402" (at 40.64 222.885 0)
      (effects (font (size 1.27 1.27) (thickness 0.15)) (justify left bottom) hide)
    )
    (property "Footprint" "kria-k26-devboard-footprints:R_0402_1005Metric" (at 49.53 227.965 0)
      (effects (font (size 1.27 1.27) (thickness 0.15)) (justify left bottom) hide)
    )
    (property "Datasheet" "https://www.bourns.com/docs/product-datasheets/cr.pdf" (at 44.45 222.885 0)
      (effects (font (size 1.27 1.27) (thickness 0.15)) (justify left bottom) hide)
    )
    (property "Manufacturer" "Bourns" (at 54.61 227.965 0)
      (effects (font (size 1.27 1.27) (thickness 0.15)) (justify left bottom) hide)
    )
    (property "MPN" "CR0402-FX-2491GLF" (at 52.07 227.965 0)
      (effects (font (size 1.27 1.27) (thickness 0.15)) (justify left bottom) hide)
    )
    (property "Val" "2k49" (at 46.99 227.3299 90)
      (effects (font (size 1.27 1.27) (thickness 0.15)) (justify left))
    )
    (property "License" "Apache-2.0" (at 19.05 243.205 0)
      (effects (font (size 1.27 1.27) (thickness 0.15)) (justify left bottom) hide)
    )
    (property "Author" "Antmicro" (at 16.51 243.205 0)
      (effects (font (size 1.27 1.27) (thickness 0.15)) (justify left bottom) hide)
    )
    (property "Tolerance" "1%" (at 34.29 243.205 0)
      (effects (font (size 1.27 1.27)) (justify left bottom) hide)
    )
    (pin "1")
    (pin "2")
    (instances
      (project "kria-k26-devboard"
        (path ""
          (reference "R68") (unit 1)
        )
      )
    )
  )

  (symbol (lib_id "kria-k26-devboard:GND") (at 44.45 232.41 0) (unit 1)
    (in_bom yes) (on_board yes) (dnp no) (fields_autoplaced)
    (property "Reference" "#PWR0105" (at 44.45 238.76 0)
      (effects (font (size 1.27 1.27)) hide)
    )
    (property "Value" "GND" (at 44.45 237.49 0)
      (effects (font (size 1.27 1.27)))
    )
    (property "Footprint" "" (at 53.34 240.03 0)
      (effects (font (size 1.27 1.27) (thickness 0.15)) (justify left bottom) hide)
    )
    (property "Datasheet" "" (at 53.34 245.11 0)
      (effects (font (size 1.27 1.27) (thickness 0.15)) (justify left bottom) hide)
    )
    (property "Author" "Antmicro" (at 53.34 240.03 0)
      (effects (font (size 1.27 1.27) (thickness 0.15)) (justify left bottom) hide)
    )
    (property "License" "Apache-2.0" (at 53.34 242.57 0)
      (effects (font (size 1.27 1.27) (thickness 0.15)) (justify left bottom) hide)
    )
    (pin "1")
    (instances
      (project "kria-k26-devboard"
        (path ""
          (reference "#PWR0105") (unit 1)
        )
      )
    )
  )

  (symbol (lib_id "kria-k26-devboard:R_10k_0402") (at 44.45 212.725 270) (unit 1)
    (in_bom yes) (on_board yes) (dnp no) (fields_autoplaced)
    (property "Reference" "R67" (at 41.91 213.995 90)
      (effects (font (size 1.524 1.524)) (justify right))
    )
    (property "Value" "R_10k_0402" (at 40.64 212.725 0)
      (effects (font (size 1.27 1.27) (thickness 0.15)) (justify left bottom) hide)
    )
    (property "Footprint" "kria-k26-devboard-footprints:R_0402_1005Metric" (at 49.53 217.805 0)
      (effects (font (size 1.27 1.27) (thickness 0.15)) (justify left bottom) hide)
    )
    (property "Datasheet" "https://www.bourns.com/docs/product-datasheets/cr.pdf" (at 44.45 212.725 0)
      (effects (font (size 1.27 1.27) (thickness 0.15)) (justify left bottom) hide)
    )
    (property "Manufacturer" "Bourns" (at 54.61 217.805 0)
      (effects (font (size 1.27 1.27) (thickness 0.15)) (justify left bottom) hide)
    )
    (property "MPN" "CR0402-FX-1002GLF" (at 52.07 217.805 0)
      (effects (font (size 1.27 1.27) (thickness 0.15)) (justify left bottom) hide)
    )
    (property "Val" "10k" (at 41.91 217.1699 90)
      (effects (font (size 1.27 1.27) (thickness 0.15)) (justify right))
    )
    (property "License" "Apache-2.0" (at 19.05 233.045 0)
      (effects (font (size 1.27 1.27) (thickness 0.15)) (justify left bottom) hide)
    )
    (property "Author" "Antmicro" (at 16.51 233.045 0)
      (effects (font (size 1.27 1.27) (thickness 0.15)) (justify left bottom) hide)
    )
    (property "Tolerance" "1%" (at 34.29 233.045 0)
      (effects (font (size 1.27 1.27)) (justify left bottom) hide)
    )
    (pin "1")
    (pin "2")
    (instances
      (project "kria-k26-devboard"
        (path ""
          (reference "R67") (unit 1)
        )
      )
    )
  )

  (symbol (lib_id "kria-k26-devboard:GND") (at 351.79 122.555 0) (mirror y) (unit 1)
    (in_bom yes) (on_board yes) (dnp no) (fields_autoplaced)
    (property "Reference" "#PWR0249" (at 351.79 128.905 0)
      (effects (font (size 1.27 1.27)) hide)
    )
    (property "Value" "GND" (at 351.79 127.635 0)
      (effects (font (size 1.27 1.27)))
    )
    (property "Footprint" "" (at 342.9 130.175 0)
      (effects (font (size 1.27 1.27) (thickness 0.15)) (justify left bottom) hide)
    )
    (property "Datasheet" "" (at 342.9 135.255 0)
      (effects (font (size 1.27 1.27) (thickness 0.15)) (justify left bottom) hide)
    )
    (property "Author" "Antmicro" (at 342.9 130.175 0)
      (effects (font (size 1.27 1.27) (thickness 0.15)) (justify left bottom) hide)
    )
    (property "License" "Apache-2.0" (at 342.9 132.715 0)
      (effects (font (size 1.27 1.27) (thickness 0.15)) (justify left bottom) hide)
    )
    (pin "1")
    (instances
      (project "kria-k26-devboard"
        (path ""
          (reference "#PWR0249") (unit 1)
        )
      )
    )
  )

  (symbol (lib_id "kria-k26-devboard:GND") (at 60.96 85.09 0) (unit 1)
    (in_bom yes) (on_board yes) (dnp no) (fields_autoplaced)
    (property "Reference" "#PWR0243" (at 60.96 91.44 0)
      (effects (font (size 1.27 1.27)) hide)
    )
    (property "Value" "GND" (at 60.96 90.17 0)
      (effects (font (size 1.27 1.27)))
    )
    (property "Footprint" "" (at 69.85 92.71 0)
      (effects (font (size 1.27 1.27) (thickness 0.15)) (justify left bottom) hide)
    )
    (property "Datasheet" "" (at 69.85 97.79 0)
      (effects (font (size 1.27 1.27) (thickness 0.15)) (justify left bottom) hide)
    )
    (property "Author" "Antmicro" (at 69.85 92.71 0)
      (effects (font (size 1.27 1.27) (thickness 0.15)) (justify left bottom) hide)
    )
    (property "License" "Apache-2.0" (at 69.85 95.25 0)
      (effects (font (size 1.27 1.27) (thickness 0.15)) (justify left bottom) hide)
    )
    (pin "1")
    (instances
      (project "kria-k26-devboard"
        (path ""
          (reference "#PWR0243") (unit 1)
        )
      )
    )
  )

  (symbol (lib_id "kria-k26-devboard:GND") (at 49.53 125.73 0) (unit 1)
    (in_bom yes) (on_board yes) (dnp no) (fields_autoplaced)
    (property "Reference" "#PWR0235" (at 49.53 132.08 0)
      (effects (font (size 1.27 1.27)) hide)
    )
    (property "Value" "GND" (at 49.53 130.81 0)
      (effects (font (size 1.27 1.27)))
    )
    (property "Footprint" "" (at 58.42 133.35 0)
      (effects (font (size 1.27 1.27) (thickness 0.15)) (justify left bottom) hide)
    )
    (property "Datasheet" "" (at 58.42 138.43 0)
      (effects (font (size 1.27 1.27) (thickness 0.15)) (justify left bottom) hide)
    )
    (property "Author" "Antmicro" (at 58.42 133.35 0)
      (effects (font (size 1.27 1.27) (thickness 0.15)) (justify left bottom) hide)
    )
    (property "License" "Apache-2.0" (at 58.42 135.89 0)
      (effects (font (size 1.27 1.27) (thickness 0.15)) (justify left bottom) hide)
    )
    (pin "1")
    (instances
      (project "kria-k26-devboard"
        (path ""
          (reference "#PWR0235") (unit 1)
        )
      )
    )
  )

  (symbol (lib_id "kria-k26-devboard:GND") (at 222.885 111.76 0) (mirror y) (unit 1)
    (in_bom yes) (on_board yes) (dnp no) (fields_autoplaced)
    (property "Reference" "#PWR0245" (at 222.885 118.11 0)
      (effects (font (size 1.27 1.27)) hide)
    )
    (property "Value" "GND" (at 222.885 116.84 0)
      (effects (font (size 1.27 1.27)))
    )
    (property "Footprint" "" (at 213.995 119.38 0)
      (effects (font (size 1.27 1.27) (thickness 0.15)) (justify left bottom) hide)
    )
    (property "Datasheet" "" (at 213.995 124.46 0)
      (effects (font (size 1.27 1.27) (thickness 0.15)) (justify left bottom) hide)
    )
    (property "Author" "Antmicro" (at 213.995 119.38 0)
      (effects (font (size 1.27 1.27) (thickness 0.15)) (justify left bottom) hide)
    )
    (property "License" "Apache-2.0" (at 213.995 121.92 0)
      (effects (font (size 1.27 1.27) (thickness 0.15)) (justify left bottom) hide)
    )
    (pin "1")
    (instances
      (project "kria-k26-devboard"
        (path ""
          (reference "#PWR0245") (unit 1)
        )
      )
    )
  )

  (symbol (lib_id "kria-k26-devboard:GND") (at 39.37 125.73 0) (unit 1)
    (in_bom yes) (on_board yes) (dnp no) (fields_autoplaced)
    (property "Reference" "#PWR0236" (at 39.37 132.08 0)
      (effects (font (size 1.27 1.27)) hide)
    )
    (property "Value" "GND" (at 39.37 130.81 0)
      (effects (font (size 1.27 1.27)))
    )
    (property "Footprint" "" (at 48.26 133.35 0)
      (effects (font (size 1.27 1.27) (thickness 0.15)) (justify left bottom) hide)
    )
    (property "Datasheet" "" (at 48.26 138.43 0)
      (effects (font (size 1.27 1.27) (thickness 0.15)) (justify left bottom) hide)
    )
    (property "Author" "Antmicro" (at 48.26 133.35 0)
      (effects (font (size 1.27 1.27) (thickness 0.15)) (justify left bottom) hide)
    )
    (property "License" "Apache-2.0" (at 48.26 135.89 0)
      (effects (font (size 1.27 1.27) (thickness 0.15)) (justify left bottom) hide)
    )
    (pin "1")
    (instances
      (project "kria-k26-devboard"
        (path ""
          (reference "#PWR0236") (unit 1)
        )
      )
    )
  )

  (symbol (lib_id "kria-k26-devboard:GND") (at 71.12 67.31 0) (unit 1)
    (in_bom yes) (on_board yes) (dnp no) (fields_autoplaced)
    (property "Reference" "#PWR0233" (at 71.12 73.66 0)
      (effects (font (size 1.27 1.27)) hide)
    )
    (property "Value" "GND" (at 71.12 72.39 0)
      (effects (font (size 1.27 1.27)))
    )
    (property "Footprint" "" (at 80.01 74.93 0)
      (effects (font (size 1.27 1.27) (thickness 0.15)) (justify left bottom) hide)
    )
    (property "Datasheet" "" (at 80.01 80.01 0)
      (effects (font (size 1.27 1.27) (thickness 0.15)) (justify left bottom) hide)
    )
    (property "Author" "Antmicro" (at 80.01 74.93 0)
      (effects (font (size 1.27 1.27) (thickness 0.15)) (justify left bottom) hide)
    )
    (property "License" "Apache-2.0" (at 80.01 77.47 0)
      (effects (font (size 1.27 1.27) (thickness 0.15)) (justify left bottom) hide)
    )
    (pin "1")
    (instances
      (project "kria-k26-devboard"
        (path ""
          (reference "#PWR0233") (unit 1)
        )
      )
    )
  )

  (symbol (lib_id "kria-k26-devboard:GND") (at 351.79 91.44 0) (mirror y) (unit 1)
    (in_bom yes) (on_board yes) (dnp no) (fields_autoplaced)
    (property "Reference" "#PWR0246" (at 351.79 97.79 0)
      (effects (font (size 1.27 1.27)) hide)
    )
    (property "Value" "GND" (at 351.79 96.52 0)
      (effects (font (size 1.27 1.27)))
    )
    (property "Footprint" "" (at 342.9 99.06 0)
      (effects (font (size 1.27 1.27) (thickness 0.15)) (justify left bottom) hide)
    )
    (property "Datasheet" "" (at 342.9 104.14 0)
      (effects (font (size 1.27 1.27) (thickness 0.15)) (justify left bottom) hide)
    )
    (property "Author" "Antmicro" (at 342.9 99.06 0)
      (effects (font (size 1.27 1.27) (thickness 0.15)) (justify left bottom) hide)
    )
    (property "License" "Apache-2.0" (at 342.9 101.6 0)
      (effects (font (size 1.27 1.27) (thickness 0.15)) (justify left bottom) hide)
    )
    (pin "1")
    (instances
      (project "kria-k26-devboard"
        (path ""
          (reference "#PWR0246") (unit 1)
        )
      )
    )
  )

  (symbol (lib_id "kria-k26-devboard:GND") (at 227.33 111.76 0) (mirror y) (unit 1)
    (in_bom yes) (on_board yes) (dnp no) (fields_autoplaced)
    (property "Reference" "#PWR0405" (at 227.33 118.11 0)
      (effects (font (size 1.27 1.27)) hide)
    )
    (property "Value" "GND" (at 227.33 116.84 0)
      (effects (font (size 1.27 1.27)))
    )
    (property "Footprint" "" (at 218.44 119.38 0)
      (effects (font (size 1.27 1.27) (thickness 0.15)) (justify left bottom) hide)
    )
    (property "Datasheet" "" (at 218.44 124.46 0)
      (effects (font (size 1.27 1.27) (thickness 0.15)) (justify left bottom) hide)
    )
    (property "Author" "Antmicro" (at 218.44 119.38 0)
      (effects (font (size 1.27 1.27) (thickness 0.15)) (justify left bottom) hide)
    )
    (property "License" "Apache-2.0" (at 218.44 121.92 0)
      (effects (font (size 1.27 1.27) (thickness 0.15)) (justify left bottom) hide)
    )
    (pin "1")
    (instances
      (project "kria-k26-devboard"
        (path ""
          (reference "#PWR0405") (unit 1)
        )
      )
    )
  )

  (symbol (lib_id "kria-k26-devboard:GND") (at 72.39 144.78 0) (unit 1)
    (in_bom yes) (on_board yes) (dnp no) (fields_autoplaced)
    (property "Reference" "#PWR0239" (at 72.39 151.13 0)
      (effects (font (size 1.27 1.27)) hide)
    )
    (property "Value" "GND" (at 72.39 149.86 0)
      (effects (font (size 1.27 1.27)))
    )
    (property "Footprint" "" (at 81.28 152.4 0)
      (effects (font (size 1.27 1.27) (thickness 0.15)) (justify left bottom) hide)
    )
    (property "Datasheet" "" (at 81.28 157.48 0)
      (effects (font (size 1.27 1.27) (thickness 0.15)) (justify left bottom) hide)
    )
    (property "Author" "Antmicro" (at 81.28 152.4 0)
      (effects (font (size 1.27 1.27) (thickness 0.15)) (justify left bottom) hide)
    )
    (property "License" "Apache-2.0" (at 81.28 154.94 0)
      (effects (font (size 1.27 1.27) (thickness 0.15)) (justify left bottom) hide)
    )
    (pin "1")
    (instances
      (project "kria-k26-devboard"
        (path ""
          (reference "#PWR0239") (unit 1)
        )
      )
    )
  )

  (symbol (lib_id "kria-k26-devboard:GND") (at 60.96 67.31 0) (unit 1)
    (in_bom yes) (on_board yes) (dnp no) (fields_autoplaced)
    (property "Reference" "#PWR0234" (at 60.96 73.66 0)
      (effects (font (size 1.27 1.27)) hide)
    )
    (property "Value" "GND" (at 60.96 72.39 0)
      (effects (font (size 1.27 1.27)))
    )
    (property "Footprint" "" (at 69.85 74.93 0)
      (effects (font (size 1.27 1.27) (thickness 0.15)) (justify left bottom) hide)
    )
    (property "Datasheet" "" (at 69.85 80.01 0)
      (effects (font (size 1.27 1.27) (thickness 0.15)) (justify left bottom) hide)
    )
    (property "Author" "Antmicro" (at 69.85 74.93 0)
      (effects (font (size 1.27 1.27) (thickness 0.15)) (justify left bottom) hide)
    )
    (property "License" "Apache-2.0" (at 69.85 77.47 0)
      (effects (font (size 1.27 1.27) (thickness 0.15)) (justify left bottom) hide)
    )
    (pin "1")
    (instances
      (project "kria-k26-devboard"
        (path ""
          (reference "#PWR0234") (unit 1)
        )
      )
    )
  )

  (symbol (lib_id "kria-k26-devboard:GND") (at 38.1 85.725 0) (unit 1)
    (in_bom yes) (on_board yes) (dnp no) (fields_autoplaced)
    (property "Reference" "#PWR0229" (at 38.1 92.075 0)
      (effects (font (size 1.27 1.27)) hide)
    )
    (property "Value" "GND" (at 38.1 90.805 0)
      (effects (font (size 1.27 1.27)))
    )
    (property "Footprint" "" (at 46.99 93.345 0)
      (effects (font (size 1.27 1.27) (thickness 0.15)) (justify left bottom) hide)
    )
    (property "Datasheet" "" (at 46.99 98.425 0)
      (effects (font (size 1.27 1.27) (thickness 0.15)) (justify left bottom) hide)
    )
    (property "Author" "Antmicro" (at 46.99 93.345 0)
      (effects (font (size 1.27 1.27) (thickness 0.15)) (justify left bottom) hide)
    )
    (property "License" "Apache-2.0" (at 46.99 95.885 0)
      (effects (font (size 1.27 1.27) (thickness 0.15)) (justify left bottom) hide)
    )
    (pin "1")
    (instances
      (project "kria-k26-devboard"
        (path ""
          (reference "#PWR0229") (unit 1)
        )
      )
    )
  )

  (symbol (lib_id "kria-k26-devboard:GND") (at 379.73 100.33 0) (mirror y) (unit 1)
    (in_bom yes) (on_board yes) (dnp no) (fields_autoplaced)
    (property "Reference" "#PWR0250" (at 379.73 106.68 0)
      (effects (font (size 1.27 1.27)) hide)
    )
    (property "Value" "GND" (at 379.73 105.41 0)
      (effects (font (size 1.27 1.27)))
    )
    (property "Footprint" "" (at 370.84 107.95 0)
      (effects (font (size 1.27 1.27) (thickness 0.15)) (justify left bottom) hide)
    )
    (property "Datasheet" "" (at 370.84 113.03 0)
      (effects (font (size 1.27 1.27) (thickness 0.15)) (justify left bottom) hide)
    )
    (property "Author" "Antmicro" (at 370.84 107.95 0)
      (effects (font (size 1.27 1.27) (thickness 0.15)) (justify left bottom) hide)
    )
    (property "License" "Apache-2.0" (at 370.84 110.49 0)
      (effects (font (size 1.27 1.27) (thickness 0.15)) (justify left bottom) hide)
    )
    (pin "1")
    (instances
      (project "kria-k26-devboard"
        (path ""
          (reference "#PWR0250") (unit 1)
        )
      )
    )
  )

  (symbol (lib_id "kria-k26-devboard:C_100n_0402") (at 222.885 106.68 270) (unit 1)
    (in_bom yes) (on_board yes) (dnp no) (fields_autoplaced)
    (property "Reference" "C239" (at 220.345 107.9563 90)
      (effects (font (size 1.524 1.524)) (justify right))
    )
    (property "Value" "C_100n_0402" (at 219.075 106.68 0)
      (effects (font (size 1.27 1.27) (thickness 0.15)) (justify left bottom) hide)
    )
    (property "Footprint" "kria-k26-devboard-footprints:C_0402_1005Metric" (at 227.965 111.76 0)
      (effects (font (size 1.27 1.27) (thickness 0.15)) (justify left bottom) hide)
    )
    (property "Datasheet" "https://search.murata.co.jp/Ceramy/image/img/A01X/G101/ENG/GRM155R61H104KE14-01.pdf" (at 222.885 106.68 0)
      (effects (font (size 1.27 1.27) (thickness 0.15)) (justify left bottom) hide)
    )
    (property "Manufacturer" "Murata" (at 233.045 111.76 0)
      (effects (font (size 1.27 1.27) (thickness 0.15)) (justify left bottom) hide)
    )
    (property "MPN" "GRM155R61H104KE14D" (at 230.505 111.76 0)
      (effects (font (size 1.27 1.27) (thickness 0.15)) (justify left bottom) hide)
    )
    (property "Val" "100n" (at 220.345 111.1312 90)
      (effects (font (size 1.27 1.27) (thickness 0.15)) (justify right))
    )
    (property "License" "Apache-2.0" (at 200.025 127 0)
      (effects (font (size 1.27 1.27) (thickness 0.15)) (justify left bottom) hide)
    )
    (property "Author" "Antmicro" (at 197.485 127 0)
      (effects (font (size 1.27 1.27) (thickness 0.15)) (justify left bottom) hide)
    )
    (property "Voltage" "50V" (at 194.945 127 0)
      (effects (font (size 1.27 1.27)) (justify left bottom) hide)
    )
    (property "Dielectric" "X5R" (at 192.405 127 0)
      (effects (font (size 1.27 1.27)) (justify left bottom) hide)
    )
    (pin "1")
    (pin "2")
    (instances
      (project "kria-k26-devboard"
        (path ""
          (reference "C239") (unit 1)
        )
      )
    )
  )

  (symbol (lib_id "kria-k26-devboard:GND") (at 351.536 76.2 0) (mirror y) (unit 1)
    (in_bom yes) (on_board yes) (dnp no) (fields_autoplaced)
    (property "Reference" "#PWR0248" (at 351.536 82.55 0)
      (effects (font (size 1.27 1.27)) hide)
    )
    (property "Value" "GND" (at 351.536 81.28 0)
      (effects (font (size 1.27 1.27)))
    )
    (property "Footprint" "" (at 342.646 83.82 0)
      (effects (font (size 1.27 1.27) (thickness 0.15)) (justify left bottom) hide)
    )
    (property "Datasheet" "" (at 342.646 88.9 0)
      (effects (font (size 1.27 1.27) (thickness 0.15)) (justify left bottom) hide)
    )
    (property "Author" "Antmicro" (at 342.646 83.82 0)
      (effects (font (size 1.27 1.27) (thickness 0.15)) (justify left bottom) hide)
    )
    (property "License" "Apache-2.0" (at 342.646 86.36 0)
      (effects (font (size 1.27 1.27) (thickness 0.15)) (justify left bottom) hide)
    )
    (pin "1")
    (instances
      (project "kria-k26-devboard"
        (path ""
          (reference "#PWR0248") (unit 1)
        )
      )
    )
  )

  (symbol (lib_id "kria-k26-devboard:GND") (at 62.23 144.78 0) (unit 1)
    (in_bom yes) (on_board yes) (dnp no) (fields_autoplaced)
    (property "Reference" "#PWR0240" (at 62.23 151.13 0)
      (effects (font (size 1.27 1.27)) hide)
    )
    (property "Value" "GND" (at 62.23 149.86 0)
      (effects (font (size 1.27 1.27)))
    )
    (property "Footprint" "" (at 71.12 152.4 0)
      (effects (font (size 1.27 1.27) (thickness 0.15)) (justify left bottom) hide)
    )
    (property "Datasheet" "" (at 71.12 157.48 0)
      (effects (font (size 1.27 1.27) (thickness 0.15)) (justify left bottom) hide)
    )
    (property "Author" "Antmicro" (at 71.12 152.4 0)
      (effects (font (size 1.27 1.27) (thickness 0.15)) (justify left bottom) hide)
    )
    (property "License" "Apache-2.0" (at 71.12 154.94 0)
      (effects (font (size 1.27 1.27) (thickness 0.15)) (justify left bottom) hide)
    )
    (pin "1")
    (instances
      (project "kria-k26-devboard"
        (path ""
          (reference "#PWR0240") (unit 1)
        )
      )
    )
  )

  (symbol (lib_id "kria-k26-devboard:GND") (at 72.39 125.73 0) (unit 1)
    (in_bom yes) (on_board yes) (dnp no) (fields_autoplaced)
    (property "Reference" "#PWR0237" (at 72.39 132.08 0)
      (effects (font (size 1.27 1.27)) hide)
    )
    (property "Value" "GND" (at 72.39 130.81 0)
      (effects (font (size 1.27 1.27)))
    )
    (property "Footprint" "" (at 81.28 133.35 0)
      (effects (font (size 1.27 1.27) (thickness 0.15)) (justify left bottom) hide)
    )
    (property "Datasheet" "" (at 81.28 138.43 0)
      (effects (font (size 1.27 1.27) (thickness 0.15)) (justify left bottom) hide)
    )
    (property "Author" "Antmicro" (at 81.28 133.35 0)
      (effects (font (size 1.27 1.27) (thickness 0.15)) (justify left bottom) hide)
    )
    (property "License" "Apache-2.0" (at 81.28 135.89 0)
      (effects (font (size 1.27 1.27) (thickness 0.15)) (justify left bottom) hide)
    )
    (pin "1")
    (instances
      (project "kria-k26-devboard"
        (path ""
          (reference "#PWR0237") (unit 1)
        )
      )
    )
  )

  (symbol (lib_id "kria-k26-devboard:GND") (at 71.12 85.09 0) (unit 1)
    (in_bom yes) (on_board yes) (dnp no) (fields_autoplaced)
    (property "Reference" "#PWR0244" (at 71.12 91.44 0)
      (effects (font (size 1.27 1.27)) hide)
    )
    (property "Value" "GND" (at 71.12 90.17 0)
      (effects (font (size 1.27 1.27)))
    )
    (property "Footprint" "" (at 80.01 92.71 0)
      (effects (font (size 1.27 1.27) (thickness 0.15)) (justify left bottom) hide)
    )
    (property "Datasheet" "" (at 80.01 97.79 0)
      (effects (font (size 1.27 1.27) (thickness 0.15)) (justify left bottom) hide)
    )
    (property "Author" "Antmicro" (at 80.01 92.71 0)
      (effects (font (size 1.27 1.27) (thickness 0.15)) (justify left bottom) hide)
    )
    (property "License" "Apache-2.0" (at 80.01 95.25 0)
      (effects (font (size 1.27 1.27) (thickness 0.15)) (justify left bottom) hide)
    )
    (pin "1")
    (instances
      (project "kria-k26-devboard"
        (path ""
          (reference "#PWR0244") (unit 1)
        )
      )
    )
  )

  (symbol (lib_id "kria-k26-devboard:GND") (at 71.12 104.14 0) (unit 1)
    (in_bom yes) (on_board yes) (dnp no) (fields_autoplaced)
    (property "Reference" "#PWR0241" (at 71.12 110.49 0)
      (effects (font (size 1.27 1.27)) hide)
    )
    (property "Value" "GND" (at 71.12 109.22 0)
      (effects (font (size 1.27 1.27)))
    )
    (property "Footprint" "" (at 80.01 111.76 0)
      (effects (font (size 1.27 1.27) (thickness 0.15)) (justify left bottom) hide)
    )
    (property "Datasheet" "" (at 80.01 116.84 0)
      (effects (font (size 1.27 1.27) (thickness 0.15)) (justify left bottom) hide)
    )
    (property "Author" "Antmicro" (at 80.01 111.76 0)
      (effects (font (size 1.27 1.27) (thickness 0.15)) (justify left bottom) hide)
    )
    (property "License" "Apache-2.0" (at 80.01 114.3 0)
      (effects (font (size 1.27 1.27) (thickness 0.15)) (justify left bottom) hide)
    )
    (pin "1")
    (instances
      (project "kria-k26-devboard"
        (path ""
          (reference "#PWR0241") (unit 1)
        )
      )
    )
  )

  (symbol (lib_id "kria-k26-devboard:GND") (at 60.96 104.14 0) (unit 1)
    (in_bom yes) (on_board yes) (dnp no) (fields_autoplaced)
    (property "Reference" "#PWR0242" (at 60.96 110.49 0)
      (effects (font (size 1.27 1.27)) hide)
    )
    (property "Value" "GND" (at 60.96 109.22 0)
      (effects (font (size 1.27 1.27)))
    )
    (property "Footprint" "" (at 69.85 111.76 0)
      (effects (font (size 1.27 1.27) (thickness 0.15)) (justify left bottom) hide)
    )
    (property "Datasheet" "" (at 69.85 116.84 0)
      (effects (font (size 1.27 1.27) (thickness 0.15)) (justify left bottom) hide)
    )
    (property "Author" "Antmicro" (at 69.85 111.76 0)
      (effects (font (size 1.27 1.27) (thickness 0.15)) (justify left bottom) hide)
    )
    (property "License" "Apache-2.0" (at 69.85 114.3 0)
      (effects (font (size 1.27 1.27) (thickness 0.15)) (justify left bottom) hide)
    )
    (pin "1")
    (instances
      (project "kria-k26-devboard"
        (path ""
          (reference "#PWR0242") (unit 1)
        )
      )
    )
  )

  (symbol (lib_id "kria-k26-devboard:C_100n_0402") (at 227.33 106.68 270) (unit 1)
    (in_bom yes) (on_board yes) (dnp no)
    (property "Reference" "C240" (at 229.87 107.9501 90)
      (effects (font (size 1.524 1.524)) (justify left))
    )
    (property "Value" "C_100n_0402" (at 223.52 106.68 0)
      (effects (font (size 1.27 1.27) (thickness 0.15)) (justify left bottom) hide)
    )
    (property "Footprint" "kria-k26-devboard-footprints:C_0402_1005Metric" (at 232.41 111.76 0)
      (effects (font (size 1.27 1.27) (thickness 0.15)) (justify left bottom) hide)
    )
    (property "Datasheet" "https://search.murata.co.jp/Ceramy/image/img/A01X/G101/ENG/GRM155R61H104KE14-01.pdf" (at 227.33 106.68 0)
      (effects (font (size 1.27 1.27) (thickness 0.15)) (justify left bottom) hide)
    )
    (property "Manufacturer" "Murata" (at 237.49 111.76 0)
      (effects (font (size 1.27 1.27) (thickness 0.15)) (justify left bottom) hide)
    )
    (property "MPN" "GRM155R61H104KE14D" (at 234.95 111.76 0)
      (effects (font (size 1.27 1.27) (thickness 0.15)) (justify left bottom) hide)
    )
    (property "Val" "100n" (at 229.87 111.125 90)
      (effects (font (size 1.27 1.27) (thickness 0.15)) (justify left))
    )
    (property "License" "Apache-2.0" (at 204.47 127 0)
      (effects (font (size 1.27 1.27) (thickness 0.15)) (justify left bottom) hide)
    )
    (property "Author" "Antmicro" (at 201.93 127 0)
      (effects (font (size 1.27 1.27) (thickness 0.15)) (justify left bottom) hide)
    )
    (property "Voltage" "50V" (at 199.39 127 0)
      (effects (font (size 1.27 1.27)) (justify left bottom) hide)
    )
    (property "Dielectric" "X5R" (at 196.85 127 0)
      (effects (font (size 1.27 1.27)) (justify left bottom) hide)
    )
    (pin "1")
    (pin "2")
    (instances
      (project "kria-k26-devboard"
        (path ""
          (reference "C240") (unit 1)
        )
      )
    )
  )

  (symbol (lib_id "kria-k26-devboard:GND") (at 62.23 125.73 0) (unit 1)
    (in_bom yes) (on_board yes) (dnp no) (fields_autoplaced)
    (property "Reference" "#PWR0238" (at 62.23 132.08 0)
      (effects (font (size 1.27 1.27)) hide)
    )
    (property "Value" "GND" (at 62.23 130.81 0)
      (effects (font (size 1.27 1.27)))
    )
    (property "Footprint" "" (at 71.12 133.35 0)
      (effects (font (size 1.27 1.27) (thickness 0.15)) (justify left bottom) hide)
    )
    (property "Datasheet" "" (at 71.12 138.43 0)
      (effects (font (size 1.27 1.27) (thickness 0.15)) (justify left bottom) hide)
    )
    (property "Author" "Antmicro" (at 71.12 133.35 0)
      (effects (font (size 1.27 1.27) (thickness 0.15)) (justify left bottom) hide)
    )
    (property "License" "Apache-2.0" (at 71.12 135.89 0)
      (effects (font (size 1.27 1.27) (thickness 0.15)) (justify left bottom) hide)
    )
    (pin "1")
    (instances
      (project "kria-k26-devboard"
        (path ""
          (reference "#PWR0238") (unit 1)
        )
      )
    )
  )

  (symbol (lib_id "kria-k26-devboard:GND") (at 351.79 107.95 0) (mirror y) (unit 1)
    (in_bom yes) (on_board yes) (dnp no) (fields_autoplaced)
    (property "Reference" "#PWR0247" (at 351.79 114.3 0)
      (effects (font (size 1.27 1.27)) hide)
    )
    (property "Value" "GND" (at 351.79 113.03 0)
      (effects (font (size 1.27 1.27)))
    )
    (property "Footprint" "" (at 342.9 115.57 0)
      (effects (font (size 1.27 1.27) (thickness 0.15)) (justify left bottom) hide)
    )
    (property "Datasheet" "" (at 342.9 120.65 0)
      (effects (font (size 1.27 1.27) (thickness 0.15)) (justify left bottom) hide)
    )
    (property "Author" "Antmicro" (at 342.9 115.57 0)
      (effects (font (size 1.27 1.27) (thickness 0.15)) (justify left bottom) hide)
    )
    (property "License" "Apache-2.0" (at 342.9 118.11 0)
      (effects (font (size 1.27 1.27) (thickness 0.15)) (justify left bottom) hide)
    )
    (pin "1")
    (instances
      (project "kria-k26-devboard"
        (path ""
          (reference "#PWR0247") (unit 1)
        )
      )
    )
  )
)
